FILE_TYPE = MACRO_DRAWING;
SET COLOR_WIRE YELLOW;
SET COLOR_PROP ORANGE;
SET COLOR_DOT WHITE;
SET COLOR_ARC YELLOW;
SET COLOR_BODY GREEN;
SET COLOR_NOTE PURPLE;
SET PROP_DISPLAY VALUE;
SET PAGE_NUMBER P315;
FORCEADD UNIVERSAL_POWER..1
(-3200 1725);
FORCEPROP 3 LASTPIN (-3200 1675) SIG_NAME P3V3_AUX\g
J 0
(-3190 1685);
DISPLAY 0.659574 (-3190 1685);
PAINT MONO (-3190 1685);
DISPLAY INVISIBLE (-3190 1685);
FORCEPROP 1 LAST HDL_POWER P3V3_AUX
J 1
(-3200 1775);
DISPLAY 0.617021 (-3200 1775);
PAINT GREEN (-3200 1775);
FORCEPROP 2 LAST CDS_LIB pure_quanta_power
J 0
(-3200 1725);
DISPLAY INVISIBLE (-3200 1725);
FORCEPROP 1 LAST PATH I1
J 0
(-3150 1750);
DISPLAY 0.872340 (-3150 1750);
PAINT AQUA (-3150 1750);
DISPLAY INVISIBLE (-3150 1750);
FORCEADD Q_CAP..1
(-2725 2525);
FORCEPROP 1 LAST LOCATION PC6014
J 0
(-2675 2650);
DISPLAY 0.617021 (-2675 2650);
PAINT AQUA (-2675 2650);
FORCEPROP 0 LAST $SEC 1
J 0
(-2675 2700);
DISPLAY 0.680851 (-2675 2700);
PAINT MONO (-2675 2700);
DISPLAY INVISIBLE (-2675 2700);
FORCEPROP 0 LAST CDS_SEC 1
J 0
(-2675 2700);
DISPLAY 0.680851 (-2675 2700);
DISPLAY INVISIBLE (-2675 2700);
FORCEPROP 1 LASTPIN (-2725 2625) $PN 1
J 0
(-2715 2605);
DISPLAY 0.787234 (-2715 2605);
PAINT MONO (-2715 2605);
FORCEPROP 1 LASTPIN (-2725 2425) $PN 2
J 0
(-2715 2405);
DISPLAY 0.787234 (-2715 2405);
PAINT MONO (-2715 2405);
FORCEPROP 1 LAST MATERIAL X6S
J 0
(-2675 2450);
DISPLAY 0.617021 (-2675 2450);
PAINT SKYBLUE (-2675 2450);
FORCEPROP 1 LAST PACK_TYPE C0805
J 0
(-2675 2400);
DISPLAY 0.617021 (-2675 2400);
PAINT SKYBLUE (-2675 2400);
FORCEPROP 1 LAST VALUE 22UF
J 0
(-2675 2600);
DISPLAY 0.617021 (-2675 2600);
PAINT SKYBLUE (-2675 2600);
FORCEPROP 1 LAST TOLERANCE 20%
J 0
(-2675 2500);
DISPLAY 0.617021 (-2675 2500);
PAINT SKYBLUE (-2675 2500);
FORCEPROP 1 LAST VOLTAGE 16V
J 0
(-2675 2550);
DISPLAY 0.617021 (-2675 2550);
PAINT SKYBLUE (-2675 2550);
FORCEPROP 2 LAST CDS_LIB pure_quanta
J 0
(-2725 2525);
DISPLAY INVISIBLE (-2725 2525);
FORCEPROP 1 LAST PART_NUMBER CH6223MEA01
J 0
(-2675 2350);
DISPLAY 0.617021 (-2675 2350);
PAINT BLUE (-2675 2350);
DISPLAY INVISIBLE (-2675 2350);
FORCEPROP 1 LAST PATH I10
J 0
(-2675 2675);
DISPLAY 0.978723 (-2675 2675);
PAINT WHITE (-2675 2675);
DISPLAY INVISIBLE (-2675 2675);
FORCEADD GND..1
(-2025 775);
FORCEPROP 3 LASTPIN (-2025 825) SIG_NAME GND\g
J 0
(-2015 835);
DISPLAY 0.659574 (-2015 835);
PAINT MONO (-2015 835);
DISPLAY INVISIBLE (-2015 835);
FORCEPROP 1 LAST SIZE 1B
J 0
(-1950 725);
DISPLAY 0.872340 (-1950 725);
PAINT AQUA (-1950 725);
DISPLAY INVISIBLE (-1950 725);
FORCEPROP 2 LAST CDS_LIB pure_quanta_power
J 0
(-2025 775);
DISPLAY INVISIBLE (-2025 775);
FORCEPROP 1 LAST HDL_POWER GND
J 0
(-2025 925);
DISPLAY 0.872340 (-2025 925);
PAINT GREEN (-2025 925);
DISPLAY INVISIBLE (-2025 925);
FORCEPROP 1 LAST PATH I11
J 0
(-1950 775);
DISPLAY 0.872340 (-1950 775);
PAINT AQUA (-1950 775);
DISPLAY INVISIBLE (-1950 775);
FORCEADD Q_RES..2
(-2025 975);
FORCEPROP 1 LAST LOCATION PR6003
J 0
(-1980 1100);
DISPLAY 0.978723 (-1980 1100);
FORCEPROP 0 LAST $SEC 1
J 0
(-1975 1150);
DISPLAY 0.680851 (-1975 1150);
PAINT MONO (-1975 1150);
DISPLAY INVISIBLE (-1975 1150);
FORCEPROP 0 LAST CDS_SEC 1
J 0
(-1975 1150);
DISPLAY 0.680851 (-1975 1150);
DISPLAY INVISIBLE (-1975 1150);
FORCEPROP 1 LASTPIN (-2025 1075) $PN 1
J 0
(-2020 1037);
DISPLAY 0.787234 (-2020 1037);
PAINT MONO (-2020 1037);
FORCEPROP 1 LASTPIN (-2025 875) $PN 2
J 0
(-2020 885);
DISPLAY 0.787234 (-2020 885);
PAINT MONO (-2020 885);
FORCEPROP 1 LAST PACK_TYPE 0402LF
J 0
(-1985 800);
DISPLAY 0.978723 (-1985 800);
FORCEPROP 1 LAST WATTAGE 1/16W
J 0
(-1985 950);
DISPLAY 0.978723 (-1985 950);
FORCEPROP 1 LAST MATERIAL CHIP
J 0
(-1985 900);
DISPLAY 0.978723 (-1985 900);
FORCEPROP 1 LAST VALUE 10K
J 0
(-1980 1050);
DISPLAY 0.978723 (-1980 1050);
FORCEPROP 1 LAST TOLERANCE 1%
J 0
(-1980 1000);
DISPLAY 0.978723 (-1980 1000);
FORCEPROP 2 LAST CDS_LIB pure_quanta
J 0
(-2025 975);
DISPLAY INVISIBLE (-2025 975);
FORCEPROP 1 LAST PART_NUMBER CS31002FB08
J 0
(-1985 850);
DISPLAY 0.978723 (-1985 850);
DISPLAY INVISIBLE (-1985 850);
FORCEPROP 1 LAST PATH I12
J 0
(-1975 1150);
DISPLAY 0.978723 (-1975 1150);
PAINT WHITE (-1975 1150);
DISPLAY INVISIBLE (-1975 1150);
FORCEADD Q_CAP..1
(-2225 1375);
FORCEPROP 1 LAST LOCATION PC6008
J 0
(-2375 1425);
DISPLAY 0.617021 (-2375 1425);
PAINT AQUA (-2375 1425);
FORCEPROP 0 LAST $SEC 1
J 0
(-2375 1475);
DISPLAY 0.680851 (-2375 1475);
PAINT MONO (-2375 1475);
DISPLAY INVISIBLE (-2375 1475);
FORCEPROP 0 LAST CDS_SEC 1
J 0
(-2375 1475);
DISPLAY 0.680851 (-2375 1475);
DISPLAY INVISIBLE (-2375 1475);
FORCEPROP 1 LASTPIN (-2225 1475) $PN 1
J 0
(-2215 1455);
DISPLAY 0.787234 (-2215 1455);
PAINT MONO (-2215 1455);
FORCEPROP 1 LASTPIN (-2225 1275) $PN 2
J 0
(-2215 1255);
DISPLAY 0.787234 (-2215 1255);
PAINT MONO (-2215 1255);
FORCEPROP 1 LAST VALUE 1UF
J 0
(-2375 1350);
DISPLAY 0.617021 (-2375 1350);
PAINT SKYBLUE (-2375 1350);
FORCEPROP 1 LAST VOLTAGE 25V
J 0
(-2375 1300);
DISPLAY 0.617021 (-2375 1300);
PAINT SKYBLUE (-2375 1300);
FORCEPROP 1 LAST MATERIAL X6S
J 0
(-2375 1200);
DISPLAY 0.617021 (-2375 1200);
PAINT SKYBLUE (-2375 1200);
FORCEPROP 1 LAST TOLERANCE 10%
J 0
(-2375 1250);
DISPLAY 0.617021 (-2375 1250);
PAINT SKYBLUE (-2375 1250);
FORCEPROP 1 LAST PACK_TYPE C0402
J 0
(-2400 1100);
DISPLAY 0.617021 (-2400 1100);
PAINT SKYBLUE (-2400 1100);
FORCEPROP 2 LAST CDS_LIB pure_quanta
J 0
(-2225 1375);
DISPLAY INVISIBLE (-2225 1375);
FORCEPROP 1 LAST PART_NUMBER CH5104KEB02
J 0
(-2575 1150);
DISPLAY 0.617021 (-2575 1150);
PAINT BLUE (-2575 1150);
DISPLAY INVISIBLE (-2575 1150);
FORCEPROP 1 LAST PATH I13
J 0
(-2175 1525);
DISPLAY 0.978723 (-2175 1525);
PAINT WHITE (-2175 1525);
DISPLAY INVISIBLE (-2175 1525);
FORCEADD GND..1
(-2225 1175);
FORCEPROP 3 LASTPIN (-2225 1225) SIG_NAME GND\g
J 0
(-2215 1235);
DISPLAY 0.659574 (-2215 1235);
PAINT MONO (-2215 1235);
DISPLAY INVISIBLE (-2215 1235);
FORCEPROP 1 LAST SIZE 1B
J 0
(-2150 1125);
DISPLAY 0.872340 (-2150 1125);
PAINT AQUA (-2150 1125);
DISPLAY INVISIBLE (-2150 1125);
FORCEPROP 2 LAST CDS_LIB pure_quanta_power
J 0
(-2225 1175);
DISPLAY INVISIBLE (-2225 1175);
FORCEPROP 1 LAST HDL_POWER GND
J 0
(-2225 1325);
DISPLAY 0.872340 (-2225 1325);
PAINT GREEN (-2225 1325);
DISPLAY INVISIBLE (-2225 1325);
FORCEPROP 1 LAST PATH I14
J 0
(-2150 1175);
DISPLAY 0.872340 (-2150 1175);
PAINT AQUA (-2150 1175);
DISPLAY INVISIBLE (-2150 1175);
FORCEADD Q_RES..1
(-2300 1825);
FORCEPROP 1 LAST LOCATION PR6006
J 0
(-2350 1900);
DISPLAY 0.617021 (-2350 1900);
PAINT AQUA (-2350 1900);
FORCEPROP 0 LAST $SEC 1
J 0
(-2350 1950);
DISPLAY 0.680851 (-2350 1950);
PAINT MONO (-2350 1950);
DISPLAY INVISIBLE (-2350 1950);
FORCEPROP 0 LAST CDS_SEC 1
J 0
(-2350 1950);
DISPLAY 0.680851 (-2350 1950);
DISPLAY INVISIBLE (-2350 1950);
FORCEPROP 1 LASTPIN (-2400 1825) $PN 1
J 0
(-2388 1837);
DISPLAY 0.787234 (-2388 1837);
PAINT MONO (-2388 1837);
FORCEPROP 1 LASTPIN (-2200 1825) $PN 2
J 0
(-2238 1837);
DISPLAY 0.787234 (-2238 1837);
PAINT MONO (-2238 1837);
FORCEPROP 1 LAST TOLERANCE 1%
J 0
(-2225 1750);
DISPLAY 0.617021 (-2225 1750);
PAINT SKYBLUE (-2225 1750);
FORCEPROP 1 LAST MATERIAL CHIP
J 0
(-2450 1750);
DISPLAY 0.617021 (-2450 1750);
PAINT SKYBLUE (-2450 1750);
FORCEPROP 1 LAST VALUE 60.4K
J 2
(-2400 1825);
DISPLAY 0.617021 (-2400 1825);
PAINT SKYBLUE (-2400 1825);
FORCEPROP 1 LAST WATTAGE 1/16W
J 2
(-2325 1700);
DISPLAY 0.617021 (-2325 1700);
PAINT SKYBLUE (-2325 1700);
FORCEPROP 1 LAST PACK_TYPE 0402LF
J 0
(-2300 1700);
DISPLAY 0.617021 (-2300 1700);
PAINT SKYBLUE (-2300 1700);
FORCEPROP 2 LAST CDS_LIB pure_quanta
J 0
(-2300 1825);
DISPLAY INVISIBLE (-2300 1825);
FORCEPROP 1 LAST PART_NUMBER CS36042FB04
J 0
(-2550 1650);
DISPLAY 0.617021 (-2550 1650);
PAINT BLUE (-2550 1650);
DISPLAY INVISIBLE (-2550 1650);
FORCEPROP 1 LAST PATH I15
J 0
(-2350 1975);
DISPLAY 0.978723 (-2350 1975);
PAINT WHITE (-2350 1975);
DISPLAY INVISIBLE (-2350 1975);
FORCEADD GND..1
(-525 775);
FORCEPROP 3 LASTPIN (-525 825) SIG_NAME GND\g
J 0
(-515 835);
DISPLAY 0.659574 (-515 835);
PAINT MONO (-515 835);
DISPLAY INVISIBLE (-515 835);
FORCEPROP 1 LAST SIZE 1B
J 0
(-450 725);
DISPLAY 0.872340 (-450 725);
PAINT AQUA (-450 725);
DISPLAY INVISIBLE (-450 725);
FORCEPROP 2 LAST CDS_LIB pure_quanta_power
J 0
(-525 775);
DISPLAY INVISIBLE (-525 775);
FORCEPROP 1 LAST HDL_POWER GND
J 0
(-525 925);
DISPLAY 0.872340 (-525 925);
PAINT GREEN (-525 925);
DISPLAY INVISIBLE (-525 925);
FORCEPROP 1 LAST PATH I17
J 0
(-450 775);
DISPLAY 0.872340 (-450 775);
PAINT AQUA (-450 775);
DISPLAY INVISIBLE (-450 775);
FORCEADD MPQ8626GDZ..1
(-1075 1850);
FORCEPROP 1 LAST LOCATION PU6000
J 0
(-1295 2881);
DISPLAY 0.617021 (-1295 2881);
PAINT AQUA (-1295 2881);
FORCEPROP 2 LAST SEC 1
J 0
(-1275 3025);
DISPLAY 0.680851 (-1275 3025);
PAINT MONO (-1275 3025);
DISPLAY INVISIBLE (-1275 3025);
FORCEPROP 2 LASTPIN (-675 1175) $PN 7
J 0
(-665 1185);
DISPLAY 0.680851 (-665 1185);
PAINT MONO (-665 1185);
FORCEPROP 2 LASTPIN (-675 2325) $PN 10
J 0
(-665 2335);
DISPLAY 0.680851 (-665 2335);
PAINT MONO (-665 2335);
FORCEPROP 2 LASTPIN (-1475 1225) $PN 4
J 2
(-1485 1235);
DISPLAY 0.680851 (-1485 1235);
PAINT MONO (-1485 1235);
FORCEPROP 2 LASTPIN (-1475 2025) $PN 5
J 2
(-1485 2035);
DISPLAY 0.680851 (-1485 2035);
PAINT MONO (-1485 2035);
FORCEPROP 2 LASTPIN (-675 1575) $PN 6
J 0
(-665 1585);
DISPLAY 0.680851 (-665 1585);
PAINT MONO (-665 1585);
FORCEPROP 2 LASTPIN (-1475 1825) $PN 12
J 2
(-1485 1835);
DISPLAY 0.680851 (-1485 1835);
PAINT MONO (-1485 1835);
FORCEPROP 2 LASTPIN (-675 1425) $PN 1
J 0
(-665 1435);
DISPLAY 0.680851 (-665 1435);
PAINT MONO (-665 1435);
FORCEPROP 2 LASTPIN (-675 1225) $PN 14
J 0
(-665 1235);
DISPLAY 0.680851 (-665 1235);
PAINT MONO (-665 1235);
FORCEPROP 2 LASTPIN (-675 2525) $PN 9
J 0
(-665 2535);
DISPLAY 0.680851 (-665 2535);
PAINT MONO (-665 2535);
FORCEPROP 2 LASTPIN (-675 2075) $PN 2
J 0
(-665 2085);
DISPLAY 0.680851 (-665 2085);
PAINT MONO (-665 2085);
FORCEPROP 2 LASTPIN (-675 2025) $PN 11
J 0
(-665 2035);
DISPLAY 0.680851 (-665 2035);
PAINT MONO (-665 2035);
FORCEPROP 2 LASTPIN (-675 1325) $PN 8
J 0
(-665 1335);
DISPLAY 0.680851 (-665 1335);
PAINT MONO (-665 1335);
FORCEPROP 2 LASTPIN (-1475 1575) $PN 13
J 2
(-1485 1585);
DISPLAY 0.680851 (-1485 1585);
PAINT MONO (-1485 1585);
FORCEPROP 2 LASTPIN (-1475 2525) $PN 3
J 2
(-1485 2535);
DISPLAY 0.680851 (-1485 2535);
PAINT MONO (-1485 2535);
FORCEPROP 2 LAST PART_TYPE SMLF
J 0
(-1275 2975);
DISPLAY 0.680851 (-1275 2975);
FORCEPROP 1 LAST MATERIAL IC
J 0
(-1295 2607);
DISPLAY 0.617021 (-1295 2607);
PAINT SKYBLUE (-1295 2607);
FORCEPROP 2 LAST VALUE MPQ8626GD-Z
J 0
(-1275 2925);
DISPLAY 0.617021 (-1275 2925);
PAINT SKYBLUE (-1275 2925);
FORCEPROP 1 LAST NEEDS_NO_SIZE TRUE
J 0
(-1075 1850);
DISPLAY 0.723404 (-1075 1850);
PAINT GREEN (-1075 1850);
DISPLAY INVISIBLE (-1075 1850);
FORCEPROP 1 LAST CDS_LMAN_SYM_OUTLINE -250,725,250,-725
J 0
(-1075 1850);
DISPLAY 0.468085 (-1075 1850);
PAINT GREEN (-1075 1850);
DISPLAY INVISIBLE (-1075 1850);
FORCEPROP 2 LAST CDS_LIB pure_quanta
J 0
(-1075 1850);
DISPLAY INVISIBLE (-1075 1850);
FORCEPROP 2 LAST SEC_TYPE 
J 0
(-1275 3025);
DISPLAY 1.021277 (-1275 3025);
DISPLAY INVISIBLE (-1275 3025);
FORCEPROP 1 LAST PART_NUMBER AL008626000
J 0
(-1295 2734);
DISPLAY 0.617021 (-1295 2734);
PAINT BLUE (-1295 2734);
DISPLAY INVISIBLE (-1295 2734);
FORCEPROP 1 LAST PATH I18
J 0
(-1075 1850);
DISPLAY 0.723404 (-1075 1850);
PAINT GREEN (-1075 1850);
DISPLAY INVISIBLE (-1075 1850);
FORCEADD Q_CAP..1
(-2125 2525);
FORCEPROP 1 LAST LOCATION PC6010
J 0
(-2075 2650);
DISPLAY 0.617021 (-2075 2650);
PAINT AQUA (-2075 2650);
FORCEPROP 0 LAST $SEC 1
J 0
(-2075 2700);
DISPLAY 0.680851 (-2075 2700);
PAINT MONO (-2075 2700);
DISPLAY INVISIBLE (-2075 2700);
FORCEPROP 0 LAST CDS_SEC 1
J 0
(-2075 2700);
DISPLAY 0.680851 (-2075 2700);
DISPLAY INVISIBLE (-2075 2700);
FORCEPROP 1 LASTPIN (-2125 2625) $PN 1
J 0
(-2115 2605);
DISPLAY 0.787234 (-2115 2605);
PAINT MONO (-2115 2605);
FORCEPROP 1 LASTPIN (-2125 2425) $PN 2
J 0
(-2115 2405);
DISPLAY 0.787234 (-2115 2405);
PAINT MONO (-2115 2405);
FORCEPROP 1 LAST TOLERANCE 10%
J 0
(-2075 2500);
DISPLAY 0.617021 (-2075 2500);
PAINT SKYBLUE (-2075 2500);
FORCEPROP 1 LAST MATERIAL X6S
J 0
(-2075 2450);
DISPLAY 0.617021 (-2075 2450);
PAINT SKYBLUE (-2075 2450);
FORCEPROP 1 LAST VALUE 1UF
J 0
(-2075 2600);
DISPLAY 0.617021 (-2075 2600);
PAINT SKYBLUE (-2075 2600);
FORCEPROP 1 LAST VOLTAGE 25V
J 0
(-2075 2550);
DISPLAY 0.617021 (-2075 2550);
PAINT SKYBLUE (-2075 2550);
FORCEPROP 1 LAST PACK_TYPE C0402
J 0
(-2075 2400);
DISPLAY 0.617021 (-2075 2400);
PAINT SKYBLUE (-2075 2400);
FORCEPROP 2 LAST CDS_LIB pure_quanta
J 0
(-2125 2525);
DISPLAY INVISIBLE (-2125 2525);
FORCEPROP 1 LAST PART_NUMBER CH5104KEB02
J 0
(-2075 2350);
DISPLAY 0.617021 (-2075 2350);
PAINT BLUE (-2075 2350);
DISPLAY INVISIBLE (-2075 2350);
FORCEPROP 1 LAST PATH I19
J 0
(-2075 2675);
DISPLAY 0.978723 (-2075 2675);
PAINT WHITE (-2075 2675);
DISPLAY INVISIBLE (-2075 2675);
FORCEADD Q_RES..2
R 3
(-2825 1575);
FORCEPROP 1 LAST LOCATION R6242
R 1
J 2
(-2950 1530);
DISPLAY 0.617021 (-2950 1530);
PAINT AQUA (-2950 1530);
FORCEPROP 0 LAST $SEC 1
R 1
J 0
(-2725 1625);
DISPLAY 0.680851 (-2725 1625);
PAINT MONO (-2725 1625);
DISPLAY INVISIBLE (-2725 1625);
FORCEPROP 0 LAST CDS_SEC 1
R 1
J 0
(-2725 1625);
DISPLAY 0.680851 (-2725 1625);
DISPLAY INVISIBLE (-2725 1625);
FORCEPROP 1 LASTPIN (-2925 1575) $PN 1
R 1
J 2
(-2887 1570);
DISPLAY 0.787234 (-2887 1570);
PAINT MONO (-2887 1570);
FORCEPROP 1 LASTPIN (-2725 1575) $PN 2
R 1
J 2
(-2735 1570);
DISPLAY 0.787234 (-2735 1570);
PAINT MONO (-2735 1570);
FORCEPROP 1 LAST WATTAGE 1/16W
R 1
J 2
(-2800 1535);
DISPLAY 0.617021 (-2800 1535);
PAINT SKYBLUE (-2800 1535);
FORCEPROP 1 LAST TOLERANCE 5%
R 1
J 2
(-2850 1530);
DISPLAY 0.617021 (-2850 1530);
PAINT SKYBLUE (-2850 1530);
FORCEPROP 1 LAST VALUE 0
R 1
J 2
(-2900 1530);
DISPLAY 0.617021 (-2900 1530);
PAINT SKYBLUE (-2900 1530);
FORCEPROP 1 LAST MATERIAL CHIP
R 1
J 2
(-2750 1535);
DISPLAY 0.617021 (-2750 1535);
PAINT SKYBLUE (-2750 1535);
FORCEPROP 1 LAST PACK_TYPE 0402LF
R 1
J 2
(-2650 1535);
DISPLAY 0.617021 (-2650 1535);
PAINT SKYBLUE (-2650 1535);
FORCEPROP 2 LAST CDS_LIB pure_quanta
J 0
(-2825 1575);
DISPLAY INVISIBLE (-2825 1575);
FORCEPROP 1 LAST PART_NUMBER CS00002JB13
R 1
J 2
(-2700 1535);
DISPLAY 0.617021 (-2700 1535);
PAINT BLUE (-2700 1535);
DISPLAY INVISIBLE (-2700 1535);
FORCEPROP 1 LAST PATH I2
R 1
J 2
(-3000 1525);
DISPLAY 0.978723 (-3000 1525);
PAINT WHITE (-3000 1525);
DISPLAY INVISIBLE (-3000 1525);
FORCEADD GND..1
(-125 775);
FORCEPROP 3 LASTPIN (-125 825) SIG_NAME GND\g
J 0
(-115 835);
DISPLAY 0.659574 (-115 835);
PAINT MONO (-115 835);
DISPLAY INVISIBLE (-115 835);
FORCEPROP 1 LAST SIZE 1B
J 0
(-50 725);
DISPLAY 0.872340 (-50 725);
PAINT AQUA (-50 725);
DISPLAY INVISIBLE (-50 725);
FORCEPROP 2 LAST CDS_LIB pure_quanta_power
J 0
(-125 775);
DISPLAY INVISIBLE (-125 775);
FORCEPROP 1 LAST HDL_POWER GND
J 0
(-125 925);
DISPLAY 0.872340 (-125 925);
PAINT GREEN (-125 925);
DISPLAY INVISIBLE (-125 925);
FORCEPROP 1 LAST PATH I20
J 0
(-50 775);
DISPLAY 0.872340 (-50 775);
PAINT AQUA (-50 775);
DISPLAY INVISIBLE (-50 775);
FORCEADD Q_CAP..1
(-125 1050);
FORCEPROP 1 LAST LOCATION PC384
J 0
(-75 1150);
DISPLAY 0.617021 (-75 1150);
PAINT AQUA (-75 1150);
FORCEPROP 0 LAST $SEC 1
J 0
(-75 1200);
DISPLAY 0.680851 (-75 1200);
PAINT MONO (-75 1200);
DISPLAY INVISIBLE (-75 1200);
FORCEPROP 0 LAST CDS_SEC 1
J 0
(-75 1200);
DISPLAY 0.680851 (-75 1200);
DISPLAY INVISIBLE (-75 1200);
FORCEPROP 1 LASTPIN (-125 1150) $PN 1
J 0
(-115 1130);
DISPLAY 0.787234 (-115 1130);
PAINT MONO (-115 1130);
FORCEPROP 1 LASTPIN (-125 950) $PN 2
J 0
(-115 930);
DISPLAY 0.787234 (-115 930);
PAINT MONO (-115 930);
FORCEPROP 1 LAST MATERIAL X7R
J 0
(-75 950);
DISPLAY 0.617021 (-75 950);
PAINT SKYBLUE (-75 950);
FORCEPROP 1 LAST TOLERANCE 10%
J 0
(-75 1000);
DISPLAY 0.617021 (-75 1000);
PAINT SKYBLUE (-75 1000);
FORCEPROP 1 LAST PACK_TYPE 0402
J 0
(-75 850);
DISPLAY 0.617021 (-75 850);
PAINT SKYBLUE (-75 850);
FORCEPROP 1 LAST VOLTAGE 50V
J 0
(-75 1050);
DISPLAY 0.617021 (-75 1050);
PAINT SKYBLUE (-75 1050);
FORCEPROP 1 LAST VALUE 3300PF
J 0
(-75 1100);
DISPLAY 0.617021 (-75 1100);
PAINT SKYBLUE (-75 1100);
FORCEPROP 2 LAST CDS_LIB pure_quanta
J 0
(-125 1050);
DISPLAY INVISIBLE (-125 1050);
FORCEPROP 1 LAST PART_NUMBER TMP_QCH2336K1B12
J 0
(-75 900);
DISPLAY 0.617021 (-75 900);
PAINT BLUE (-75 900);
DISPLAY INVISIBLE (-75 900);
FORCEPROP 1 LAST PATH I21
J 0
(-75 1200);
DISPLAY 0.978723 (-75 1200);
PAINT WHITE (-75 1200);
DISPLAY INVISIBLE (-75 1200);
FORCEADD GND..1
(475 675);
FORCEPROP 3 LASTPIN (475 725) SIG_NAME GND\g
J 0
(485 735);
DISPLAY 0.659574 (485 735);
PAINT MONO (485 735);
DISPLAY INVISIBLE (485 735);
FORCEPROP 1 LAST SIZE 1B
J 0
(550 625);
DISPLAY 0.872340 (550 625);
PAINT AQUA (550 625);
DISPLAY INVISIBLE (550 625);
FORCEPROP 2 LAST CDS_LIB pure_quanta_power
J 0
(475 675);
DISPLAY INVISIBLE (475 675);
FORCEPROP 1 LAST HDL_POWER GND
J 0
(475 825);
DISPLAY 0.872340 (475 825);
PAINT GREEN (475 825);
DISPLAY INVISIBLE (475 825);
FORCEPROP 1 LAST PATH I22
J 0
(550 675);
DISPLAY 0.872340 (550 675);
PAINT AQUA (550 675);
DISPLAY INVISIBLE (550 675);
FORCEADD Q_RES..2
(475 900);
FORCEPROP 1 LAST LOCATION PR6010
J 0
(520 1025);
DISPLAY 0.617021 (520 1025);
PAINT AQUA (520 1025);
FORCEPROP 0 LAST $SEC 1
J 0
(525 1075);
DISPLAY 0.680851 (525 1075);
PAINT MONO (525 1075);
DISPLAY INVISIBLE (525 1075);
FORCEPROP 0 LAST CDS_SEC 1
J 0
(525 1075);
DISPLAY 0.680851 (525 1075);
DISPLAY INVISIBLE (525 1075);
FORCEPROP 1 LASTPIN (475 1000) $PN 1
J 0
(480 962);
DISPLAY 0.787234 (480 962);
PAINT MONO (480 962);
FORCEPROP 1 LASTPIN (475 800) $PN 2
J 0
(480 810);
DISPLAY 0.787234 (480 810);
PAINT MONO (480 810);
FORCEPROP 1 LAST PACK_TYPE 0402LF
J 0
(515 725);
DISPLAY 0.617021 (515 725);
PAINT SKYBLUE (515 725);
FORCEPROP 1 LAST MATERIAL CHIP
J 0
(515 825);
DISPLAY 0.617021 (515 825);
PAINT SKYBLUE (515 825);
FORCEPROP 1 LAST WATTAGE 1/16W
J 0
(515 875);
DISPLAY 0.617021 (515 875);
PAINT SKYBLUE (515 875);
FORCEPROP 1 LAST VALUE 10K
J 0
(520 975);
DISPLAY 0.617021 (520 975);
PAINT SKYBLUE (520 975);
FORCEPROP 1 LAST TOLERANCE 1%
J 0
(520 925);
DISPLAY 0.617021 (520 925);
PAINT SKYBLUE (520 925);
FORCEPROP 2 LAST CDS_LIB pure_quanta
J 0
(475 900);
DISPLAY INVISIBLE (475 900);
FORCEPROP 1 LAST PART_NUMBER CS31002FB08
J 0
(515 775);
DISPLAY 0.617021 (515 775);
PAINT BLUE (515 775);
DISPLAY INVISIBLE (515 775);
FORCEPROP 1 LAST PATH I23
J 0
(525 1075);
DISPLAY 0.978723 (525 1075);
PAINT WHITE (525 1075);
DISPLAY INVISIBLE (525 1075);
FORCEADD GND..1
(175 1275);
FORCEPROP 3 LASTPIN (175 1325) SIG_NAME GND\g
J 0
(185 1335);
DISPLAY 0.659574 (185 1335);
PAINT MONO (185 1335);
DISPLAY INVISIBLE (185 1335);
FORCEPROP 1 LAST SIZE 1B
J 0
(250 1225);
DISPLAY 0.872340 (250 1225);
PAINT AQUA (250 1225);
DISPLAY INVISIBLE (250 1225);
FORCEPROP 2 LAST CDS_LIB pure_quanta_power
J 0
(175 1275);
DISPLAY INVISIBLE (175 1275);
FORCEPROP 1 LAST HDL_POWER GND
J 0
(175 1425);
DISPLAY 0.872340 (175 1425);
PAINT GREEN (175 1425);
DISPLAY INVISIBLE (175 1425);
FORCEPROP 1 LAST PATH I24
J 0
(250 1275);
DISPLAY 0.872340 (250 1275);
PAINT AQUA (250 1275);
DISPLAY INVISIBLE (250 1275);
FORCEADD Q_INDUCTOR..1
(825 2050);
FORCEPROP 1 LAST LOCATION PL6000
J 0
(775 2150);
DISPLAY 0.617021 (775 2150);
PAINT AQUA (775 2150);
FORCEPROP 0 LAST $SEC 1
J 0
(775 2350);
DISPLAY 0.680851 (775 2350);
PAINT MONO (775 2350);
DISPLAY INVISIBLE (775 2350);
FORCEPROP 0 LAST CDS_SEC 1
J 0
(775 2350);
DISPLAY 0.680851 (775 2350);
DISPLAY INVISIBLE (775 2350);
FORCEPROP 0 LASTPIN (725 2025) $PN 1
J 2
(715 2035);
DISPLAY 0.680851 (715 2035);
PAINT MONO (715 2035);
FORCEPROP 0 LASTPIN (925 2025) $PN 2
J 0
(935 2035);
DISPLAY 0.680851 (935 2035);
PAINT MONO (935 2035);
FORCEPROP 1 LAST MATERIAL IND
J 0
(775 2100);
DISPLAY 0.617021 (775 2100);
PAINT SKYBLUE (775 2100);
FORCEPROP 2 LAST PACK_TYPE SMLF
J 0
(775 2245);
DISPLAY 0.617021 (775 2245);
PAINT SKYBLUE (775 2245);
FORCEPROP 2 LAST VALUE 3.3UH/6A
J 0
(775 2300);
DISPLAY 0.617021 (775 2300);
PAINT SKYBLUE (775 2300);
FORCEPROP 1 LAST NEEDS_NO_SIZE TRUE
J 0
(825 2050);
DISPLAY 0.468085 (825 2050);
PAINT GREEN (825 2050);
DISPLAY INVISIBLE (825 2050);
FORCEPROP 2 LAST CDS_LIB pure_quanta
J 0
(825 2050);
DISPLAY INVISIBLE (825 2050);
FORCEPROP 1 LAST PART_NUMBER CV-3360MZ07
J 0
(775 2200);
DISPLAY 0.617021 (775 2200);
PAINT SKYBLUE (775 2200);
DISPLAY INVISIBLE (775 2200);
FORCEPROP 1 LAST PATH I25
J 0
(900 2105);
DISPLAY 0.723404 (900 2105);
PAINT GREEN (900 2105);
DISPLAY INVISIBLE (900 2105);
FORCEADD Q_CAP..2
(1525 825);
FORCEPROP 1 LAST LOCATION PC6019
J 1
(1525 900);
DISPLAY 0.617021 (1525 900);
PAINT AQUA (1525 900);
FORCEPROP 0 LAST $SEC 1
J 0
(1525 950);
DISPLAY 0.680851 (1525 950);
PAINT MONO (1525 950);
DISPLAY INVISIBLE (1525 950);
FORCEPROP 0 LAST CDS_SEC 1
J 0
(1525 950);
DISPLAY 0.680851 (1525 950);
DISPLAY INVISIBLE (1525 950);
FORCEPROP 1 LASTPIN (1425 825) $PN 1
J 0
(1415 840);
DISPLAY 0.787234 (1415 840);
PAINT MONO (1415 840);
FORCEPROP 1 LASTPIN (1625 825) $PN 2
J 0
(1610 840);
DISPLAY 0.787234 (1610 840);
PAINT MONO (1610 840);
FORCEPROP 1 LAST MATERIAL X7R
J 0
(1475 575);
DISPLAY 0.617021 (1475 575);
PAINT SKYBLUE (1475 575);
FORCEPROP 1 LAST VOLTAGE 50V
J 0
(1375 650);
DISPLAY 0.617021 (1375 650);
PAINT SKYBLUE (1375 650);
FORCEPROP 1 LAST PACK_TYPE 0402
J 1
(1550 500);
DISPLAY 0.617021 (1550 500);
PAINT SKYBLUE (1550 500);
FORCEPROP 1 LAST VALUE 330PF
J 2
(1675 725);
DISPLAY 0.617021 (1675 725);
PAINT SKYBLUE (1675 725);
FORCEPROP 1 LAST TOLERANCE 10%
J 2
(1650 650);
DISPLAY 0.617021 (1650 650);
PAINT SKYBLUE (1650 650);
FORCEPROP 2 LAST CDS_LIB pure_quanta
J 0
(1525 825);
DISPLAY INVISIBLE (1525 825);
FORCEPROP 1 LAST PART_NUMBER CH1336K1B02
J 1
(1550 450);
DISPLAY 0.617021 (1550 450);
PAINT BLUE (1550 450);
DISPLAY INVISIBLE (1550 450);
FORCEPROP 1 LAST PATH I26
J 0
(1525 1025);
DISPLAY 0.978723 (1525 1025);
PAINT WHITE (1525 1025);
DISPLAY INVISIBLE (1525 1025);
FORCEADD Q_CAP..1
(1025 1825);
FORCEPROP 1 LAST LOCATION PC6021
J 0
(1075 1925);
DISPLAY 0.617021 (1075 1925);
PAINT AQUA (1075 1925);
FORCEPROP 0 LAST $SEC 1
J 0
(1075 1975);
DISPLAY 0.680851 (1075 1975);
PAINT MONO (1075 1975);
DISPLAY INVISIBLE (1075 1975);
FORCEPROP 0 LAST CDS_SEC 1
J 0
(1075 1975);
DISPLAY 0.680851 (1075 1975);
DISPLAY INVISIBLE (1075 1975);
FORCEPROP 1 LASTPIN (1025 1925) $PN 1
J 0
(1035 1905);
DISPLAY 0.787234 (1035 1905);
PAINT MONO (1035 1905);
FORCEPROP 1 LASTPIN (1025 1725) $PN 2
J 0
(1035 1705);
DISPLAY 0.787234 (1035 1705);
PAINT MONO (1035 1705);
FORCEPROP 1 LAST VOLTAGE 50V
J 0
(1075 1825);
DISPLAY 0.617021 (1075 1825);
PAINT SKYBLUE (1075 1825);
FORCEPROP 1 LAST PACK_TYPE C0402
J 0
(1075 1625);
DISPLAY 0.617021 (1075 1625);
PAINT SKYBLUE (1075 1625);
FORCEPROP 1 LAST VALUE 100NF
J 0
(1075 1875);
DISPLAY 0.617021 (1075 1875);
PAINT SKYBLUE (1075 1875);
FORCEPROP 1 LAST MATERIAL X7R
J 0
(1075 1725);
DISPLAY 0.617021 (1075 1725);
PAINT SKYBLUE (1075 1725);
FORCEPROP 1 LAST TOLERANCE 10%
J 0
(1075 1775);
DISPLAY 0.617021 (1075 1775);
PAINT SKYBLUE (1075 1775);
FORCEPROP 2 LAST CDS_LIB pure_quanta
J 0
(1025 1825);
DISPLAY INVISIBLE (1025 1825);
FORCEPROP 1 LAST PART_NUMBER CH4106K1B01
J 0
(1075 1675);
DISPLAY 0.617021 (1075 1675);
PAINT BLUE (1075 1675);
DISPLAY INVISIBLE (1075 1675);
FORCEPROP 1 LAST PATH I27
J 0
(1075 1975);
DISPLAY 0.978723 (1075 1975);
PAINT WHITE (1075 1975);
DISPLAY INVISIBLE (1075 1975);
FORCEADD Q_RES..1
(1525 1250);
FORCEPROP 1 LAST LOCATION PR6007
J 0
(1500 1325);
DISPLAY 0.617021 (1500 1325);
PAINT AQUA (1500 1325);
FORCEPROP 0 LAST $SEC 1
J 0
(1500 1375);
DISPLAY 0.680851 (1500 1375);
PAINT MONO (1500 1375);
DISPLAY INVISIBLE (1500 1375);
FORCEPROP 0 LAST CDS_SEC 1
J 0
(1500 1375);
DISPLAY 0.680851 (1500 1375);
DISPLAY INVISIBLE (1500 1375);
FORCEPROP 1 LASTPIN (1425 1250) $PN 1
J 0
(1437 1262);
DISPLAY 0.787234 (1437 1262);
PAINT MONO (1437 1262);
FORCEPROP 1 LASTPIN (1625 1250) $PN 2
J 0
(1587 1262);
DISPLAY 0.787234 (1587 1262);
PAINT MONO (1587 1262);
FORCEPROP 1 LAST TOLERANCE 1%
J 0
(1575 1125);
DISPLAY 0.617021 (1575 1125);
PAINT SKYBLUE (1575 1125);
FORCEPROP 1 LAST VALUE 20K
J 2
(1550 1125);
DISPLAY 0.617021 (1550 1125);
PAINT SKYBLUE (1550 1125);
FORCEPROP 1 LAST WATTAGE 1/16W
J 2
(1500 1050);
DISPLAY 0.617021 (1500 1050);
PAINT SKYBLUE (1500 1050);
FORCEPROP 1 LAST PACK_TYPE 0402LF
J 0
(1525 1050);
DISPLAY 0.617021 (1525 1050);
PAINT SKYBLUE (1525 1050);
FORCEPROP 1 LAST MATERIAL CHIP
J 0
(1525 1100);
DISPLAY 0.978723 (1525 1100);
PAINT SKYBLUE (1525 1100);
DISPLAY INVISIBLE (1525 1100);
FORCEPROP 2 LAST CDS_LIB pure_quanta
J 0
(1525 1250);
DISPLAY INVISIBLE (1525 1250);
FORCEPROP 1 LAST PART_NUMBER CS32002FB06
J 0
(1275 975);
DISPLAY 0.617021 (1275 975);
PAINT BLUE (1275 975);
DISPLAY INVISIBLE (1275 975);
FORCEPROP 1 LAST PATH I28
J 0
(1475 1400);
DISPLAY 0.978723 (1475 1400);
PAINT WHITE (1475 1400);
DISPLAY INVISIBLE (1475 1400);
FORCEADD Q_CAP..1
(1400 1825);
FORCEPROP 1 LAST LOCATION PC865
J 0
(1450 1925);
DISPLAY 0.617021 (1450 1925);
PAINT AQUA (1450 1925);
FORCEPROP 0 LAST $SEC 1
J 0
(1450 1975);
DISPLAY 0.680851 (1450 1975);
PAINT MONO (1450 1975);
DISPLAY INVISIBLE (1450 1975);
FORCEPROP 0 LAST CDS_SEC 1
J 0
(1450 1975);
DISPLAY 0.680851 (1450 1975);
DISPLAY INVISIBLE (1450 1975);
FORCEPROP 1 LASTPIN (1400 1925) $PN 1
J 0
(1410 1905);
DISPLAY 0.787234 (1410 1905);
PAINT MONO (1410 1905);
FORCEPROP 1 LASTPIN (1400 1725) $PN 2
J 0
(1410 1705);
DISPLAY 0.787234 (1410 1705);
PAINT MONO (1410 1705);
FORCEPROP 1 LAST TOLERANCE 20%
J 0
(1450 1775);
DISPLAY 0.617021 (1450 1775);
PAINT SKYBLUE (1450 1775);
FORCEPROP 1 LAST MATERIAL X6S
J 0
(1450 1725);
DISPLAY 0.617021 (1450 1725);
PAINT SKYBLUE (1450 1725);
FORCEPROP 1 LAST PACK_TYPE C0805
J 0
(1450 1625);
DISPLAY 0.617021 (1450 1625);
PAINT SKYBLUE (1450 1625);
FORCEPROP 1 LAST VOLTAGE 4V
J 0
(1450 1825);
DISPLAY 0.617021 (1450 1825);
PAINT SKYBLUE (1450 1825);
FORCEPROP 1 LAST VALUE 22UF
J 0
(1450 1875);
DISPLAY 0.617021 (1450 1875);
PAINT SKYBLUE (1450 1875);
FORCEPROP 2 LAST CDS_LIB pure_quanta
J 0
(1400 1825);
DISPLAY INVISIBLE (1400 1825);
FORCEPROP 1 LAST PART_NUMBER CH622KMEA03
J 0
(1450 1675);
DISPLAY 0.617021 (1450 1675);
PAINT BLUE (1450 1675);
DISPLAY INVISIBLE (1450 1675);
FORCEPROP 1 LAST PATH I29
J 0
(1450 1975);
DISPLAY 0.978723 (1450 1975);
PAINT WHITE (1450 1975);
DISPLAY INVISIBLE (1450 1975);
FORCEADD GND..1
(-2725 1675);
FORCEPROP 3 LASTPIN (-2725 1725) SIG_NAME GND\g
J 0
(-2715 1735);
DISPLAY 0.659574 (-2715 1735);
PAINT MONO (-2715 1735);
DISPLAY INVISIBLE (-2715 1735);
FORCEPROP 1 LAST SIZE 1B
J 0
(-2650 1625);
DISPLAY 0.872340 (-2650 1625);
PAINT AQUA (-2650 1625);
DISPLAY INVISIBLE (-2650 1625);
FORCEPROP 2 LAST CDS_LIB pure_quanta_power
J 0
(-2725 1675);
DISPLAY INVISIBLE (-2725 1675);
FORCEPROP 1 LAST HDL_POWER GND
J 0
(-2725 1825);
DISPLAY 0.872340 (-2725 1825);
PAINT GREEN (-2725 1825);
DISPLAY INVISIBLE (-2725 1825);
FORCEPROP 1 LAST PATH I3
J 0
(-2650 1675);
DISPLAY 0.872340 (-2650 1675);
PAINT AQUA (-2650 1675);
DISPLAY INVISIBLE (-2650 1675);
FORCEADD Q_CAP..1
(350 2200);
FORCEPROP 1 LAST LOCATION PC641
J 0
(400 2425);
DISPLAY 0.617021 (400 2425);
PAINT AQUA (400 2425);
FORCEPROP 0 LAST $SEC 1
J 0
(400 2475);
DISPLAY 0.680851 (400 2475);
PAINT MONO (400 2475);
DISPLAY INVISIBLE (400 2475);
FORCEPROP 0 LAST CDS_SEC 1
J 0
(400 2475);
DISPLAY 0.680851 (400 2475);
DISPLAY INVISIBLE (400 2475);
FORCEPROP 1 LASTPIN (350 2300) $PN 1
J 0
(360 2280);
DISPLAY 0.787234 (360 2280);
PAINT MONO (360 2280);
FORCEPROP 1 LASTPIN (350 2100) $PN 2
J 0
(360 2080);
DISPLAY 0.787234 (360 2080);
PAINT MONO (360 2080);
FORCEPROP 1 LAST VOLTAGE 25V
J 0
(400 2325);
DISPLAY 0.617021 (400 2325);
PAINT SKYBLUE (400 2325);
FORCEPROP 1 LAST TOLERANCE 10%
J 0
(400 2275);
DISPLAY 0.617021 (400 2275);
PAINT SKYBLUE (400 2275);
FORCEPROP 1 LAST VALUE 0.22UF
J 0
(400 2375);
DISPLAY 0.617021 (400 2375);
PAINT SKYBLUE (400 2375);
FORCEPROP 1 LAST MATERIAL X7R
J 0
(400 2225);
DISPLAY 0.617021 (400 2225);
PAINT SKYBLUE (400 2225);
FORCEPROP 1 LAST PACK_TYPE C0402
J 0
(400 2125);
DISPLAY 0.617021 (400 2125);
PAINT SKYBLUE (400 2125);
FORCEPROP 2 LAST CDS_LIB pure_quanta
J 0
(350 2200);
DISPLAY INVISIBLE (350 2200);
FORCEPROP 1 LAST PART_NUMBER CH4224K1B01
J 0
(400 2175);
DISPLAY 0.617021 (400 2175);
PAINT SKYBLUE (400 2175);
DISPLAY INVISIBLE (400 2175);
FORCEPROP 1 LAST PATH I30
J 0
(400 2350);
DISPLAY 0.978723 (400 2350);
PAINT WHITE (400 2350);
DISPLAY INVISIBLE (400 2350);
FORCEADD Q_RES..2
(25 2825);
FORCEPROP 1 LAST LOCATION R6243
J 0
(70 2950);
DISPLAY 0.617021 (70 2950);
PAINT AQUA (70 2950);
FORCEPROP 0 LAST $SEC 1
J 0
(75 3000);
DISPLAY 0.680851 (75 3000);
PAINT MONO (75 3000);
DISPLAY INVISIBLE (75 3000);
FORCEPROP 0 LAST CDS_SEC 1
J 0
(75 3000);
DISPLAY 0.680851 (75 3000);
DISPLAY INVISIBLE (75 3000);
FORCEPROP 1 LASTPIN (25 2925) $PN 1
J 0
(30 2887);
DISPLAY 0.787234 (30 2887);
PAINT MONO (30 2887);
FORCEPROP 1 LASTPIN (25 2725) $PN 2
J 0
(30 2735);
DISPLAY 0.787234 (30 2735);
PAINT MONO (30 2735);
FORCEPROP 1 LAST VALUE 10K
J 0
(70 2900);
DISPLAY 0.617021 (70 2900);
PAINT SKYBLUE (70 2900);
FORCEPROP 1 LAST TOLERANCE 1%
J 0
(70 2850);
DISPLAY 0.617021 (70 2850);
PAINT SKYBLUE (70 2850);
FORCEPROP 1 LAST PACK_TYPE 0402LF
J 0
(65 2650);
DISPLAY 0.617021 (65 2650);
PAINT SKYBLUE (65 2650);
FORCEPROP 1 LAST MATERIAL CHIP
J 0
(65 2750);
DISPLAY 0.617021 (65 2750);
PAINT SKYBLUE (65 2750);
FORCEPROP 1 LAST WATTAGE 1/16W
J 0
(65 2800);
DISPLAY 0.617021 (65 2800);
PAINT SKYBLUE (65 2800);
FORCEPROP 2 LAST CDS_LIB pure_quanta
J 0
(25 2825);
DISPLAY INVISIBLE (25 2825);
FORCEPROP 1 LAST PART_NUMBER CS31002FB08
J 0
(65 2700);
DISPLAY 0.617021 (65 2700);
PAINT BLUE (65 2700);
DISPLAY INVISIBLE (65 2700);
FORCEPROP 1 LAST PATH I32
J 0
(75 3000);
DISPLAY 0.978723 (75 3000);
PAINT WHITE (75 3000);
DISPLAY INVISIBLE (75 3000);
FORCEADD UNIVERSAL_POWER..1
(25 3125);
FORCEPROP 3 LASTPIN (25 3075) SIG_NAME P3V3_AUX\g
J 0
(35 3085);
DISPLAY 0.659574 (35 3085);
PAINT MONO (35 3085);
DISPLAY INVISIBLE (35 3085);
FORCEPROP 1 LAST HDL_POWER P3V3_AUX
J 1
(25 3175);
DISPLAY 0.617021 (25 3175);
PAINT GREEN (25 3175);
FORCEPROP 2 LAST CDS_LIB pure_quanta_power
J 0
(25 3125);
DISPLAY INVISIBLE (25 3125);
FORCEPROP 1 LAST PATH I33
J 0
(75 3150);
DISPLAY 0.872340 (75 3150);
PAINT AQUA (75 3150);
DISPLAY INVISIBLE (75 3150);
FORCEADD Q_CAP..1
(1775 1825);
FORCEPROP 1 LAST LOCATION PC866
J 0
(1825 1925);
DISPLAY 0.617021 (1825 1925);
PAINT AQUA (1825 1925);
FORCEPROP 0 LAST $SEC 1
J 0
(1825 1975);
DISPLAY 0.680851 (1825 1975);
PAINT MONO (1825 1975);
DISPLAY INVISIBLE (1825 1975);
FORCEPROP 0 LAST CDS_SEC 1
J 0
(1825 1975);
DISPLAY 0.680851 (1825 1975);
DISPLAY INVISIBLE (1825 1975);
FORCEPROP 1 LASTPIN (1775 1925) $PN 1
J 0
(1785 1905);
DISPLAY 0.787234 (1785 1905);
PAINT MONO (1785 1905);
FORCEPROP 1 LASTPIN (1775 1725) $PN 2
J 0
(1785 1705);
DISPLAY 0.787234 (1785 1705);
PAINT MONO (1785 1705);
FORCEPROP 1 LAST PACK_TYPE C0805
J 0
(1825 1625);
DISPLAY 0.617021 (1825 1625);
PAINT SKYBLUE (1825 1625);
FORCEPROP 1 LAST MATERIAL X6S
J 0
(1825 1725);
DISPLAY 0.617021 (1825 1725);
PAINT SKYBLUE (1825 1725);
FORCEPROP 1 LAST TOLERANCE 20%
J 0
(1825 1775);
DISPLAY 0.617021 (1825 1775);
PAINT SKYBLUE (1825 1775);
FORCEPROP 1 LAST VOLTAGE 4V
J 0
(1825 1825);
DISPLAY 0.617021 (1825 1825);
PAINT SKYBLUE (1825 1825);
FORCEPROP 1 LAST VALUE 22UF
J 0
(1825 1875);
DISPLAY 0.617021 (1825 1875);
PAINT SKYBLUE (1825 1875);
FORCEPROP 2 LAST CDS_LIB pure_quanta
J 0
(1775 1825);
DISPLAY INVISIBLE (1775 1825);
FORCEPROP 1 LAST PART_NUMBER CH622KMEA03
J 0
(1825 1675);
DISPLAY 0.617021 (1825 1675);
PAINT BLUE (1825 1675);
DISPLAY INVISIBLE (1825 1675);
FORCEPROP 1 LAST PATH I34
J 0
(1825 1975);
DISPLAY 0.978723 (1825 1975);
PAINT WHITE (1825 1975);
DISPLAY INVISIBLE (1825 1975);
FORCEADD GND..1
(2075 1475);
FORCEPROP 3 LASTPIN (2075 1525) SIG_NAME GND\g
J 0
(2085 1535);
DISPLAY 0.659574 (2085 1535);
PAINT MONO (2085 1535);
DISPLAY INVISIBLE (2085 1535);
FORCEPROP 1 LAST SIZE 1B
J 0
(2150 1425);
DISPLAY 0.872340 (2150 1425);
PAINT AQUA (2150 1425);
DISPLAY INVISIBLE (2150 1425);
FORCEPROP 2 LAST CDS_LIB pure_quanta_power
J 0
(2075 1475);
DISPLAY INVISIBLE (2075 1475);
FORCEPROP 1 LAST HDL_POWER GND
J 0
(2075 1625);
DISPLAY 0.872340 (2075 1625);
PAINT GREEN (2075 1625);
DISPLAY INVISIBLE (2075 1625);
FORCEPROP 1 LAST PATH I35
J 0
(2150 1475);
DISPLAY 0.872340 (2150 1475);
PAINT AQUA (2150 1475);
DISPLAY INVISIBLE (2150 1475);
FORCEADD Q_CAP..1
(2275 1825);
FORCEPROP 1 LAST LOCATION PC867
J 0
(2325 1925);
DISPLAY 0.617021 (2325 1925);
PAINT AQUA (2325 1925);
FORCEPROP 0 LAST $SEC 1
J 0
(2325 1975);
DISPLAY 0.680851 (2325 1975);
PAINT MONO (2325 1975);
DISPLAY INVISIBLE (2325 1975);
FORCEPROP 0 LAST CDS_SEC 1
J 0
(2325 1975);
DISPLAY 0.680851 (2325 1975);
DISPLAY INVISIBLE (2325 1975);
FORCEPROP 1 LASTPIN (2275 1925) $PN 1
J 0
(2285 1905);
DISPLAY 0.787234 (2285 1905);
PAINT MONO (2285 1905);
FORCEPROP 1 LASTPIN (2275 1725) $PN 2
J 0
(2285 1705);
DISPLAY 0.787234 (2285 1705);
PAINT MONO (2285 1705);
FORCEPROP 1 LAST PACK_TYPE C0805
J 0
(2325 1625);
DISPLAY 0.617021 (2325 1625);
PAINT SKYBLUE (2325 1625);
FORCEPROP 1 LAST MATERIAL X6S
J 0
(2325 1725);
DISPLAY 0.617021 (2325 1725);
PAINT SKYBLUE (2325 1725);
FORCEPROP 1 LAST TOLERANCE 20%
J 0
(2325 1775);
DISPLAY 0.617021 (2325 1775);
PAINT SKYBLUE (2325 1775);
FORCEPROP 1 LAST VALUE 22UF
J 0
(2325 1875);
DISPLAY 0.617021 (2325 1875);
PAINT SKYBLUE (2325 1875);
FORCEPROP 1 LAST VOLTAGE 4V
J 0
(2325 1825);
DISPLAY 0.617021 (2325 1825);
PAINT SKYBLUE (2325 1825);
FORCEPROP 2 LAST CDS_LIB pure_quanta
J 0
(2275 1825);
DISPLAY INVISIBLE (2275 1825);
FORCEPROP 1 LAST PART_NUMBER CH622KMEA03
J 0
(2325 1675);
DISPLAY 0.617021 (2325 1675);
PAINT BLUE (2325 1675);
DISPLAY INVISIBLE (2325 1675);
FORCEPROP 1 LAST PATH I36
J 0
(2325 1975);
DISPLAY 0.978723 (2325 1975);
PAINT WHITE (2325 1975);
DISPLAY INVISIBLE (2325 1975);
FORCEADD Q_CAP..1
(2775 1825);
FORCEPROP 1 LAST LOCATION PC850
J 0
(2825 1925);
DISPLAY 0.617021 (2825 1925);
PAINT AQUA (2825 1925);
FORCEPROP 0 LAST $SEC 1
J 0
(2825 1975);
DISPLAY 0.680851 (2825 1975);
PAINT MONO (2825 1975);
DISPLAY INVISIBLE (2825 1975);
FORCEPROP 0 LAST CDS_SEC 1
J 0
(2825 1975);
DISPLAY 0.680851 (2825 1975);
DISPLAY INVISIBLE (2825 1975);
FORCEPROP 1 LASTPIN (2775 1925) $PN 1
J 0
(2785 1905);
DISPLAY 0.787234 (2785 1905);
PAINT MONO (2785 1905);
FORCEPROP 1 LASTPIN (2775 1725) $PN 2
J 0
(2785 1705);
DISPLAY 0.787234 (2785 1705);
PAINT MONO (2785 1705);
FORCEPROP 1 LAST VOLTAGE 4V
J 0
(2825 1825);
DISPLAY 0.617021 (2825 1825);
PAINT SKYBLUE (2825 1825);
FORCEPROP 1 LAST TOLERANCE 20%
J 0
(2825 1775);
DISPLAY 0.617021 (2825 1775);
PAINT SKYBLUE (2825 1775);
FORCEPROP 1 LAST PACK_TYPE C0805
J 0
(2825 1625);
DISPLAY 0.617021 (2825 1625);
PAINT SKYBLUE (2825 1625);
FORCEPROP 1 LAST VALUE 22UF
J 0
(2825 1875);
DISPLAY 0.617021 (2825 1875);
PAINT SKYBLUE (2825 1875);
FORCEPROP 1 LAST MATERIAL X6S
J 0
(2825 1725);
DISPLAY 0.617021 (2825 1725);
PAINT SKYBLUE (2825 1725);
FORCEPROP 2 LAST CDS_LIB pure_quanta
J 0
(2775 1825);
DISPLAY INVISIBLE (2775 1825);
FORCEPROP 1 LAST PART_NUMBER CH622KMEA03
J 0
(2825 1675);
DISPLAY 0.617021 (2825 1675);
PAINT BLUE (2825 1675);
DISPLAY INVISIBLE (2825 1675);
FORCEPROP 1 LAST PATH I37
J 0
(2825 1975);
DISPLAY 0.978723 (2825 1975);
PAINT WHITE (2825 1975);
DISPLAY INVISIBLE (2825 1975);
FORCEADD UNIVERSAL_POWER..1
(2275 2175);
FORCEPROP 3 LASTPIN (2275 2125) SIG_NAME P1V8_AUX\g
J 0
(2285 2135);
DISPLAY 0.659574 (2285 2135);
PAINT MONO (2285 2135);
DISPLAY INVISIBLE (2285 2135);
FORCEPROP 1 LAST HDL_POWER P1V8_AUX
J 1
(2275 2225);
DISPLAY 0.617021 (2275 2225);
PAINT GREEN (2275 2225);
FORCEPROP 2 LAST CDS_LIB pure_quanta_power
J 0
(2275 2175);
DISPLAY INVISIBLE (2275 2175);
FORCEPROP 1 LAST PATH I38
J 0
(2325 2200);
DISPLAY 0.872340 (2325 2200);
PAINT AQUA (2325 2200);
DISPLAY INVISIBLE (2325 2200);
FORCEADD OFFPAGE..4
R 2
(-4825 2025);
FORCEPROP 2 LAST $XR0 190 
J 0
(-5077 2025);
DISPLAY 0.638298 (-5077 2025);
PAINT MONO (-5077 2025);
FORCEPROP 2 LAST $XR1 81 
J 0
(-5077 1989);
DISPLAY 0.638298 (-5077 1989);
PAINT MONO (-5077 1989);
FORCEPROP 2 LAST $XR2 85 
J 0
(-5077 2061);
DISPLAY 0.638298 (-5077 2061);
PAINT MONO (-5077 2061);
FORCEPROP 2 LAST CDS_LIB standard
J 0
(-4825 2025);
DISPLAY INVISIBLE (-4825 2025);
FORCEPROP 1 LAST OFFPAGE TRUE
J 2
(-5150 1900);
DISPLAY 0.872340 (-5150 1900);
PAINT GREEN (-5150 1900);
DISPLAY INVISIBLE (-5150 1900);
FORCEPROP 1 LAST COMMENT_BODY TRUE
J 2
(-4800 1925);
DISPLAY 0.872340 (-4800 1925);
PAINT GREEN (-4800 1925);
DISPLAY INVISIBLE (-4800 1925);
FORCEPROP 2 LAST PATH I39
J 0
(-4775 2100);
DISPLAY 0.680851 (-4775 2100);
DISPLAY INVISIBLE (-4775 2100);
FORCEADD GND..1
(-4125 2275);
FORCEPROP 3 LASTPIN (-4125 2325) SIG_NAME GND\g
J 0
(-4115 2335);
DISPLAY 0.659574 (-4115 2335);
PAINT MONO (-4115 2335);
DISPLAY INVISIBLE (-4115 2335);
FORCEPROP 1 LAST SIZE 1B
J 0
(-4050 2225);
DISPLAY 0.872340 (-4050 2225);
PAINT AQUA (-4050 2225);
DISPLAY INVISIBLE (-4050 2225);
FORCEPROP 2 LAST CDS_LIB pure_quanta_power
J 0
(-4125 2275);
DISPLAY INVISIBLE (-4125 2275);
FORCEPROP 1 LAST HDL_POWER GND
J 0
(-4125 2425);
DISPLAY 0.872340 (-4125 2425);
PAINT GREEN (-4125 2425);
DISPLAY INVISIBLE (-4125 2425);
FORCEPROP 1 LAST PATH I4
J 0
(-4050 2275);
DISPLAY 0.872340 (-4050 2275);
PAINT AQUA (-4050 2275);
DISPLAY INVISIBLE (-4050 2275);
FORCEADD Q_RES..1
(-3900 2025);
FORCEPROP 1 LAST LOCATION R6119
J 0
(-4150 2025);
DISPLAY 0.872340 (-4150 2025);
FORCEPROP 2 LAST SEC 1
J 0
(-3950 2225);
DISPLAY 0.680851 (-3950 2225);
PAINT MONO (-3950 2225);
DISPLAY INVISIBLE (-3950 2225);
FORCEPROP 1 LASTPIN (-4000 2025) $PN 1
J 0
(-3988 2037);
DISPLAY 0.787234 (-3988 2037);
PAINT MONO (-3988 2037);
FORCEPROP 1 LASTPIN (-3800 2025) $PN 2
J 0
(-3838 2037);
DISPLAY 0.787234 (-3838 2037);
PAINT MONO (-3838 2037);
FORCEPROP 1 LAST VALUE 0
J 2
(-3700 2025);
DISPLAY 1.021277 (-3700 2025);
FORCEPROP 1 LAST TOLERANCE 5%
J 0
(-3650 1975);
DISPLAY 1.021277 (-3650 1975);
FORCEPROP 1 LAST WATTAGE 1/16W
J 2
(-3675 1975);
DISPLAY 0.808511 (-3675 1975);
FORCEPROP 1 LAST PACK_TYPE 0402LF
J 0
(-4200 1975);
DISPLAY 0.808511 (-4200 1975);
FORCEPROP 1 LAST MATERIAL CHIP
J 0
(-4000 2100);
DISPLAY 1.021277 (-4000 2100);
FORCEPROP 2 LAST SEC_TYPE 0402LF
J 0
(-3950 2225);
DISPLAY 0.680851 (-3950 2225);
DISPLAY INVISIBLE (-3950 2225);
FORCEPROP 2 LAST CDS_LIB pure_quanta
J 0
(-3900 2025);
DISPLAY INVISIBLE (-3900 2025);
FORCEPROP 1 LAST PART_NUMBER CS00002JB13
J 0
(-4125 1925);
DISPLAY 0.808511 (-4125 1925);
DISPLAY INVISIBLE (-4125 1925);
FORCEPROP 1 LAST PATH I40
J 0
(-3950 2175);
DISPLAY 0.978723 (-3950 2175);
PAINT WHITE (-3950 2175);
DISPLAY INVISIBLE (-3950 2175);
FORCEADD Q_CAP..1
R 2
(-3525 1575);
FORCEPROP 1 LAST LOCATION C345
J 2
(-3575 1675);
DISPLAY 0.808511 (-3575 1675);
FORCEPROP 0 LAST $SEC 1
J 0
(-3575 1725);
DISPLAY 0.680851 (-3575 1725);
PAINT MONO (-3575 1725);
DISPLAY INVISIBLE (-3575 1725);
FORCEPROP 0 LAST CDS_SEC 1
J 0
(-3575 1725);
DISPLAY 0.680851 (-3575 1725);
DISPLAY INVISIBLE (-3575 1725);
FORCEPROP 1 LASTPIN (-3525 1675) $PN 1
J 2
(-3535 1655);
DISPLAY 0.787234 (-3535 1655);
PAINT MONO (-3535 1655);
FORCEPROP 1 LASTPIN (-3525 1475) $PN 2
J 2
(-3535 1455);
DISPLAY 0.787234 (-3535 1455);
PAINT MONO (-3535 1455);
FORCEPROP 1 LAST TOLERANCE 10%
J 2
(-3575 1525);
DISPLAY 0.808511 (-3575 1525);
FORCEPROP 1 LAST MATERIAL EMPTY
J 2
(-3575 1475);
DISPLAY 0.808511 (-3575 1475);
FORCEPROP 1 LAST PACK_TYPE 0402
J 2
(-3575 1375);
DISPLAY 0.808511 (-3575 1375);
FORCEPROP 1 LAST VOLTAGE 25V
J 2
(-3575 1575);
DISPLAY 0.808511 (-3575 1575);
FORCEPROP 1 LAST VALUE 0.1UF
J 2
(-3575 1625);
DISPLAY 0.808511 (-3575 1625);
FORCEPROP 2 LAST CDS_LIB pure_quanta
J 2
(-3525 1575);
DISPLAY INVISIBLE (-3525 1575);
FORCEPROP 1 LAST PART_NUMBER CH4104K1B00
J 2
(-3575 1425);
DISPLAY 0.808511 (-3575 1425);
DISPLAY INVISIBLE (-3575 1425);
FORCEPROP 1 LAST PATH I41
J 2
(-3575 1725);
DISPLAY 0.978723 (-3575 1725);
PAINT WHITE (-3575 1725);
DISPLAY INVISIBLE (-3575 1725);
FORCEADD GND..1
(-3525 1125);
FORCEPROP 3 LASTPIN (-3525 1175) SIG_NAME GND\g
J 0
(-3515 1185);
DISPLAY 0.659574 (-3515 1185);
PAINT MONO (-3515 1185);
DISPLAY INVISIBLE (-3515 1185);
FORCEPROP 1 LAST SIZE 1B
J 0
(-3450 1075);
DISPLAY 0.872340 (-3450 1075);
PAINT AQUA (-3450 1075);
DISPLAY INVISIBLE (-3450 1075);
FORCEPROP 2 LAST CDS_LIB pure_quanta_power
J 0
(-3525 1125);
DISPLAY INVISIBLE (-3525 1125);
FORCEPROP 1 LAST HDL_POWER GND
J 0
(-3525 1275);
DISPLAY 0.872340 (-3525 1275);
PAINT GREEN (-3525 1275);
DISPLAY INVISIBLE (-3525 1275);
FORCEPROP 1 LAST PATH I42
J 0
(-3450 1125);
DISPLAY 0.872340 (-3450 1125);
PAINT AQUA (-3450 1125);
DISPLAY INVISIBLE (-3450 1125);
FORCEADD OFFPAGE..5
R 2
(1275 2525);
FORCEPROP 2 LAST $XR0 81 
J 0
(1464 2525);
DISPLAY 0.638298 (1464 2525);
PAINT MONO (1464 2525);
FORCEPROP 2 LAST $XR1 148 
J 0
(1554 2525);
DISPLAY 0.638298 (1554 2525);
PAINT MONO (1554 2525);
FORCEPROP 2 LAST $XR2 255 
J 0
(1674 2525);
DISPLAY 0.638298 (1674 2525);
PAINT MONO (1674 2525);
FORCEPROP 2 LAST $XR3 271 
J 0
(1794 2525);
DISPLAY 0.638298 (1794 2525);
PAINT MONO (1794 2525);
FORCEPROP 2 LAST CDS_LIB standard
J 0
(1275 2525);
DISPLAY INVISIBLE (1275 2525);
FORCEPROP 1 LAST OFFPAGE TRUE
J 2
(950 2400);
DISPLAY 0.872340 (950 2400);
PAINT GREEN (950 2400);
DISPLAY INVISIBLE (950 2400);
FORCEPROP 1 LAST COMMENT_BODY TRUE
J 2
(1175 2450);
DISPLAY 0.872340 (1175 2450);
PAINT GREEN (1175 2450);
DISPLAY INVISIBLE (1175 2450);
FORCEPROP 2 LAST PATH I43
J 0
(1450 2600);
DISPLAY 0.680851 (1450 2600);
DISPLAY INVISIBLE (1450 2600);
FORCEADD Q_RES..1
(350 2525);
FORCEPROP 1 LAST LOCATION R214
J 0
(475 2525);
DISPLAY 0.489362 (475 2525);
PAINT SKYBLUE (475 2525);
FORCEPROP 0 LAST $SEC 1
J 0
(475 2550);
DISPLAY 0.680851 (475 2550);
PAINT MONO (475 2550);
DISPLAY INVISIBLE (475 2550);
FORCEPROP 0 LAST CDS_SEC 1
J 0
(475 2550);
DISPLAY 0.680851 (475 2550);
DISPLAY INVISIBLE (475 2550);
FORCEPROP 1 LASTPIN (250 2525) $PN 1
J 0
(262 2537);
DISPLAY 0.787234 (262 2537);
PAINT MONO (262 2537);
FORCEPROP 1 LASTPIN (450 2525) $PN 2
J 0
(412 2537);
DISPLAY 0.787234 (412 2537);
PAINT MONO (412 2537);
FORCEPROP 1 LAST VALUE 33
J 2
(225 2525);
DISPLAY 0.489362 (225 2525);
PAINT SKYBLUE (225 2525);
FORCEPROP 2 LAST CDS_LIB pure_quanta
J 0
(350 2525);
DISPLAY INVISIBLE (350 2525);
FORCEPROP 1 LAST PACK_TYPE 0402LF
J 2
(525 2450);
DISPLAY 0.489362 (525 2450);
PAINT SKYBLUE (525 2450);
DISPLAY INVISIBLE (525 2450);
FORCEPROP 1 LAST TOLERANCE 5%
J 0
(225 2500);
DISPLAY 0.489362 (225 2500);
PAINT SKYBLUE (225 2500);
DISPLAY INVISIBLE (225 2500);
FORCEPROP 1 LAST MATERIAL CHIP
J 2
(525 2500);
DISPLAY 0.489362 (525 2500);
PAINT SKYBLUE (525 2500);
DISPLAY INVISIBLE (525 2500);
FORCEPROP 1 LAST WATTAGE 1/16W
J 2
(275 2450);
DISPLAY 0.489362 (275 2450);
PAINT SKYBLUE (275 2450);
DISPLAY INVISIBLE (275 2450);
FORCEPROP 2 LAST BOM_COST MEM
J 2
(375 2675);
DISPLAY 0.744681 (375 2675);
PAINT WHITE (375 2675);
DISPLAY INVISIBLE (375 2675);
FORCEPROP 1 LAST PART_NUMBER CS03302JB10
J 2
(450 2575);
DISPLAY 0.489362 (450 2575);
PAINT SKYBLUE (450 2575);
DISPLAY INVISIBLE (450 2575);
FORCEPROP 1 LAST PATH I44
J 0
(300 2675);
DISPLAY 0.978723 (300 2675);
PAINT WHITE (300 2675);
DISPLAY INVISIBLE (300 2675);
FORCEADD Q_RES..1
(-100 2325);
FORCEPROP 1 LAST LOCATION PR8003
J 0
(-150 2375);
DISPLAY 0.638298 (-150 2375);
FORCEPROP 2 LAST SEC 1
J 0
(-150 2525);
DISPLAY 0.680851 (-150 2525);
PAINT MONO (-150 2525);
DISPLAY INVISIBLE (-150 2525);
FORCEPROP 1 LASTPIN (-200 2325) $PN 1
J 0
(-188 2337);
DISPLAY 0.787234 (-188 2337);
PAINT MONO (-188 2337);
FORCEPROP 1 LASTPIN (0 2325) $PN 2
J 0
(-38 2337);
DISPLAY 0.787234 (-38 2337);
PAINT MONO (-38 2337);
FORCEPROP 1 LAST TOLERANCE 1%
J 0
(0 2275);
DISPLAY 0.510638 (0 2275);
FORCEPROP 1 LAST MATERIAL CHIP
J 0
(-125 2275);
DISPLAY 0.510638 (-125 2275);
FORCEPROP 1 LAST PACK_TYPE 0402LF
J 0
(-275 2275);
DISPLAY 0.510638 (-275 2275);
FORCEPROP 1 LAST VALUE 2.2
J 2
(-175 2325);
DISPLAY 0.510638 (-175 2325);
FORCEPROP 2 LAST CDS_LIB pure_quanta
J 0
(-100 2325);
DISPLAY INVISIBLE (-100 2325);
FORCEPROP 2 LAST SEC_TYPE 0402LF
J 0
(-150 2525);
DISPLAY 0.680851 (-150 2525);
DISPLAY INVISIBLE (-150 2525);
FORCEPROP 1 LAST WATTAGE 1/16W
J 2
(-125 2175);
DISPLAY 0.978723 (-125 2175);
DISPLAY INVISIBLE (-125 2175);
FORCEPROP 1 LAST PART_NUMBER CS-2202FB01
J 0
(-150 2425);
DISPLAY 0.638298 (-150 2425);
DISPLAY INVISIBLE (-150 2425);
FORCEPROP 1 LAST PATH I45
J 0
(-150 2475);
DISPLAY 0.978723 (-150 2475);
PAINT WHITE (-150 2475);
DISPLAY INVISIBLE (-150 2475);
FORCEADD Q_CAP..1
(-4125 2525);
FORCEPROP 1 LAST LOCATION PC6020
J 0
(-4075 2625);
DISPLAY 0.617021 (-4075 2625);
PAINT AQUA (-4075 2625);
FORCEPROP 0 LAST $SEC 1
J 0
(-4075 2675);
DISPLAY 0.680851 (-4075 2675);
PAINT MONO (-4075 2675);
DISPLAY INVISIBLE (-4075 2675);
FORCEPROP 0 LAST CDS_SEC 1
J 0
(-4075 2675);
DISPLAY 0.680851 (-4075 2675);
DISPLAY INVISIBLE (-4075 2675);
FORCEPROP 1 LASTPIN (-4125 2625) $PN 1
J 0
(-4115 2605);
DISPLAY 0.787234 (-4115 2605);
PAINT MONO (-4115 2605);
FORCEPROP 1 LASTPIN (-4125 2425) $PN 2
J 0
(-4115 2405);
DISPLAY 0.787234 (-4115 2405);
PAINT MONO (-4115 2405);
FORCEPROP 1 LAST MATERIAL X7R
J 0
(-4075 2425);
DISPLAY 0.617021 (-4075 2425);
PAINT SKYBLUE (-4075 2425);
FORCEPROP 1 LAST TOLERANCE 10%
J 0
(-4075 2475);
DISPLAY 0.617021 (-4075 2475);
PAINT SKYBLUE (-4075 2475);
FORCEPROP 1 LAST VOLTAGE 50V
J 0
(-4075 2525);
DISPLAY 0.617021 (-4075 2525);
PAINT SKYBLUE (-4075 2525);
FORCEPROP 1 LAST VALUE 100NF
J 0
(-4075 2575);
DISPLAY 0.617021 (-4075 2575);
PAINT SKYBLUE (-4075 2575);
FORCEPROP 1 LAST PACK_TYPE C0402
J 0
(-4075 2325);
DISPLAY 0.617021 (-4075 2325);
PAINT SKYBLUE (-4075 2325);
FORCEPROP 2 LAST CDS_LIB pure_quanta
J 0
(-4125 2525);
DISPLAY INVISIBLE (-4125 2525);
FORCEPROP 1 LAST PART_NUMBER CH4106K1B01
J 0
(-4075 2375);
DISPLAY 0.617021 (-4075 2375);
PAINT BLUE (-4075 2375);
DISPLAY INVISIBLE (-4075 2375);
FORCEPROP 1 LAST PATH I5
J 0
(-4075 2675);
DISPLAY 0.978723 (-4075 2675);
PAINT WHITE (-4075 2675);
DISPLAY INVISIBLE (-4075 2675);
FORCEADD UNIVERSAL_POWER..1
(-4125 2875);
FORCEPROP 3 LASTPIN (-4125 2825) SIG_NAME P12V_AUX\g
J 0
(-4115 2835);
DISPLAY 0.659574 (-4115 2835);
PAINT MONO (-4115 2835);
DISPLAY INVISIBLE (-4115 2835);
FORCEPROP 1 LAST HDL_POWER P12V_AUX
J 1
(-4125 2925);
DISPLAY 0.617021 (-4125 2925);
PAINT GREEN (-4125 2925);
FORCEPROP 2 LAST CDS_LIB pure_quanta_power
J 0
(-4125 2875);
DISPLAY INVISIBLE (-4125 2875);
FORCEPROP 1 LAST PATH I6
J 0
(-4075 2900);
DISPLAY 0.872340 (-4075 2900);
PAINT AQUA (-4075 2900);
DISPLAY INVISIBLE (-4075 2900);
FORCEADD Q_INDUCTOR..1
(-3625 2750);
FORCEPROP 1 LAST LOCATION PL6002
J 0
(-3675 3025);
DISPLAY 0.617021 (-3675 3025);
PAINT AQUA (-3675 3025);
FORCEPROP 0 LAST $SEC 1
J 0
(-3675 3075);
DISPLAY 0.680851 (-3675 3075);
PAINT MONO (-3675 3075);
DISPLAY INVISIBLE (-3675 3075);
FORCEPROP 0 LAST CDS_SEC 1
J 0
(-3675 3075);
DISPLAY 0.680851 (-3675 3075);
DISPLAY INVISIBLE (-3675 3075);
FORCEPROP 0 LASTPIN (-3725 2725) $PN 1
J 2
(-3735 2735);
DISPLAY 0.680851 (-3735 2735);
PAINT MONO (-3735 2735);
FORCEPROP 0 LASTPIN (-3525 2725) $PN 2
J 0
(-3515 2735);
DISPLAY 0.680851 (-3515 2735);
PAINT MONO (-3515 2735);
FORCEPROP 2 LAST VALUE BLM18SN220TN1D/8000MA
J 0
(-4000 2825);
DISPLAY 0.617021 (-4000 2825);
PAINT SKYBLUE (-4000 2825);
FORCEPROP 2 LAST PACK_TYPE SMLF
J 0
(-3625 2900);
DISPLAY 0.617021 (-3625 2900);
PAINT SKYBLUE (-3625 2900);
FORCEPROP 1 LAST MATERIAL IND
J 0
(-3750 2900);
DISPLAY 0.617021 (-3750 2900);
PAINT SKYBLUE (-3750 2900);
FORCEPROP 1 LAST NEEDS_NO_SIZE TRUE
J 0
(-3625 2750);
DISPLAY 0.468085 (-3625 2750);
PAINT GREEN (-3625 2750);
DISPLAY INVISIBLE (-3625 2750);
FORCEPROP 2 LAST CDS_LIB pure_quanta
J 0
(-3625 2750);
DISPLAY INVISIBLE (-3625 2750);
FORCEPROP 1 LAST PART_NUMBER CX220TN1001
J 0
(-3800 2975);
DISPLAY 0.617021 (-3800 2975);
PAINT BLUE (-3800 2975);
DISPLAY INVISIBLE (-3800 2975);
FORCEPROP 1 LAST PATH I7
J 0
(-3550 2805);
DISPLAY 0.723404 (-3550 2805);
PAINT GREEN (-3550 2805);
DISPLAY INVISIBLE (-3550 2805);
FORCEADD Q_CAP..1
(-3325 2525);
FORCEPROP 1 LAST LOCATION PC6012
J 0
(-3275 2650);
DISPLAY 0.617021 (-3275 2650);
PAINT AQUA (-3275 2650);
FORCEPROP 0 LAST $SEC 1
J 0
(-3275 2700);
DISPLAY 0.680851 (-3275 2700);
PAINT MONO (-3275 2700);
DISPLAY INVISIBLE (-3275 2700);
FORCEPROP 0 LAST CDS_SEC 1
J 0
(-3275 2700);
DISPLAY 0.680851 (-3275 2700);
DISPLAY INVISIBLE (-3275 2700);
FORCEPROP 1 LASTPIN (-3325 2625) $PN 1
J 0
(-3315 2605);
DISPLAY 0.787234 (-3315 2605);
PAINT MONO (-3315 2605);
FORCEPROP 1 LASTPIN (-3325 2425) $PN 2
J 0
(-3315 2405);
DISPLAY 0.787234 (-3315 2405);
PAINT MONO (-3315 2405);
FORCEPROP 1 LAST TOLERANCE 20%
J 0
(-3275 2500);
DISPLAY 0.617021 (-3275 2500);
PAINT SKYBLUE (-3275 2500);
FORCEPROP 1 LAST VOLTAGE 16V
J 0
(-3275 2550);
DISPLAY 0.617021 (-3275 2550);
PAINT SKYBLUE (-3275 2550);
FORCEPROP 1 LAST VALUE 22UF
J 0
(-3275 2600);
DISPLAY 0.617021 (-3275 2600);
PAINT SKYBLUE (-3275 2600);
FORCEPROP 1 LAST MATERIAL X6S
J 0
(-3275 2450);
DISPLAY 0.617021 (-3275 2450);
PAINT SKYBLUE (-3275 2450);
FORCEPROP 1 LAST PACK_TYPE C0805
J 0
(-3275 2400);
DISPLAY 0.617021 (-3275 2400);
PAINT SKYBLUE (-3275 2400);
FORCEPROP 2 LAST CDS_LIB pure_quanta
J 0
(-3325 2525);
DISPLAY INVISIBLE (-3325 2525);
FORCEPROP 1 LAST PART_NUMBER CH6223MEA01
J 0
(-3275 2350);
DISPLAY 0.617021 (-3275 2350);
PAINT BLUE (-3275 2350);
DISPLAY INVISIBLE (-3275 2350);
FORCEPROP 1 LAST PATH I8
J 0
(-3275 2675);
DISPLAY 0.978723 (-3275 2675);
PAINT WHITE (-3275 2675);
DISPLAY INVISIBLE (-3275 2675);
FORCEADD GND..1
(-2675 2175);
FORCEPROP 3 LASTPIN (-2675 2225) SIG_NAME GND\g
J 0
(-2665 2235);
DISPLAY 0.659574 (-2665 2235);
PAINT MONO (-2665 2235);
DISPLAY INVISIBLE (-2665 2235);
FORCEPROP 1 LAST SIZE 1B
J 0
(-2600 2125);
DISPLAY 0.872340 (-2600 2125);
PAINT AQUA (-2600 2125);
DISPLAY INVISIBLE (-2600 2125);
FORCEPROP 2 LAST CDS_LIB pure_quanta_power
J 0
(-2675 2175);
DISPLAY INVISIBLE (-2675 2175);
FORCEPROP 1 LAST HDL_POWER GND
J 0
(-2675 2325);
DISPLAY 0.872340 (-2675 2325);
PAINT GREEN (-2675 2325);
DISPLAY INVISIBLE (-2675 2325);
FORCEPROP 1 LAST PATH I9
J 0
(-2600 2175);
DISPLAY 0.872340 (-2600 2175);
PAINT AQUA (-2600 2175);
DISPLAY INVISIBLE (-2600 2175);
FORCEADD DNS..2
(-3625 1575);
PAINT RED (-3625 1575);
FORCEPROP 2 LAST CDS_LIB mstr_misc
J 0
(-3625 1575);
DISPLAY INVISIBLE (-3625 1575);
FORCEPROP 1 LAST COMMENT_BODY TRUE
R 1
J 0
(-3550 1350);
DISPLAY 0.872340 (-3550 1350);
PAINT GREEN (-3550 1350);
DISPLAY INVISIBLE (-3550 1350);
FORCEADD QUANTA_TITLE_BLOCK_C..1
(4250 -1250);
FORCEPROP 0 LAST CDS_CON_LAST_MODIFIED Thu Sep 14 16:12:47 2023
J 0
(2365 -1235);
DISPLAY INVISIBLE (2365 -1235);
FORCEPROP 1 LAST CUSTOM_TXT_CDS <CON_LAST_MODIFIED>
J 0
(2365 -1235);
DISPLAY 0.978723 (2365 -1235);
FORCEPROP 2 LAST CUSTOM_TXT_CDS <XR_PAGE_TITLE>
J 0
(-3640 4000);
DISPLAY 0.638298 (-3640 4000);
PAINT PINK (-3640 4000);
DISPLAY INVISIBLE (-3640 4000);
FORCEPROP 1 LAST CUSTOM_TXT_CDS <NAME_2>
J 0
(1075 -1200);
FORCEPROP 1 LAST CUSTOM_TXT_CDS <NAME_1>
J 0
(1075 -1075);
FORCEPROP 1 LAST CUSTOM_TXT_CDS <Q_NUMBER>
J 0
(2847 -1147);
DISPLAY 1.212766 (2847 -1147);
FORCEPROP 1 LAST CUSTOM_TXT_CDS <Q_PROJ>
J 0
(1868 -1148);
DISPLAY 1.212766 (1868 -1148);
FORCEPROP 1 LAST CUSTOM_TXT_CDS <Q_REV>
J 0
(4066 -1147);
DISPLAY 1.212766 (4066 -1147);
FORCEPROP 1 LAST CUSTOM_TXT_CDS <CON_PAGE_NUM> OF <CON_TOTAL_PAGES>
J 0
(3804 -1232);
DISPLAY 0.978723 (3804 -1232);
FORCEPROP 1 LAST Q_TITLE P1V8_AUX
J 0
(-5057 -1227);
DISPLAY 2.446809 (-5057 -1227);
PAINT GREEN (-5057 -1227);
FORCEPROP 2 LAST CDS_XR_PAGE_TITLE CR-270 : @T6G_MB_LIB.T6G(SCH_1):PAGE270
J 0
(-3640 4000);
DISPLAY 0.638298 (-3640 4000);
PAINT PINK (-3640 4000);
DISPLAY INVISIBLE (-3640 4000);
FORCEPROP 2 LAST PAGE_BORDER TRUE
J 0
(-3640 4000);
DISPLAY 0.638298 (-3640 4000);
PAINT PINK (-3640 4000);
DISPLAY INVISIBLE (-3640 4000);
FORCEPROP 1 LAST CDS_LMAN_SYM_OUTLINE -9475,6775,100,-125
J 0
(4250 -1250);
DISPLAY 0.468085 (4250 -1250);
PAINT GREEN (4250 -1250);
DISPLAY INVISIBLE (4250 -1250);
FORCEPROP 2 LAST CDS_LIB pure_quanta
J 0
(4250 -1250);
DISPLAY INVISIBLE (4250 -1250);
FORCEPROP 1 LAST COMMENT_BODY TRUE
J 0
(4262 -1263);
DISPLAY 0.978723 (4262 -1263);
PAINT GREEN (4262 -1263);
DISPLAY INVISIBLE (4262 -1263);
FORCEPROP 1 LAST Q_DEPT CCBU
J 1
(521 -1204);
DISPLAY 1.957447 (521 -1204);
PAINT GREEN (521 -1204);
DISPLAY INVISIBLE (521 -1204);
WIRE 16 -1 (-2025 875)(-2025 825);
WIRE 16 -1 (-2225 1275)(-2225 1225);
WIRE 16 -1 (-125 825)(-125 950);
WIRE 16 -1 (475 725)(475 800);
WIRE 16 -1 (-675 1425)(175 1425);
WIRE 16 -1 (175 1425)(175 1325);
WIRE 16 -1 (25 2925)(25 3075);
WIRE 16 -1 (-4125 2425)(-4125 2325);
WIRE 16 -1 (-3525 1475)(-3525 1175);
WIRE 16 -1 (-3800 2025)(-3525 2025);
WIRE 16 -1 (-3525 2025)(-1475 2025);
FORCEPROP 2 LAST SIG_NAME P1V8_AUX_ENABLE
J 0
(-2660 2060);
DISPLAY 0.765957 (-2660 2060);
FORCEPROP 2 LASTPROP $XRERR UNIQUE?
J 0
(-2900 2060);
DISPLAY 0.638298 (-2900 2060);
PAINT MONO (-2900 2060);
DISPLAY INVISIBLE (-2900 2060);
WIRE 16 -1 (-3525 2025)(-3525 1675);
WIRE 16 2175 (-4675 300)(-3000 300);
WIRE 16 2175 (-4675 300)(-4675 -175);
WIRE 16 2175 (-3000 300)(-3000 -175);
WIRE 16 2175 (-4675 -175)(-3000 -175);
WIRE 16 2175 (-4725 -825)(-3172 -825);
WIRE 16 2175 (-4725 -350)(-4725 -825);
WIRE 16 2175 (-3172 -350)(-3172 -825);
WIRE 16 2175 (-4725 -350)(-3172 -350);
WIRE 16 -1 (-3200 1575)(-2925 1575);
WIRE 16 -1 (-3200 1675)(-3200 1575);
WIRE 16 -1 (-675 1225)(-525 1225);
WIRE 16 -1 (-525 1225)(-525 1175);
WIRE 16 -1 (-675 1175)(-525 1175);
WIRE 16 -1 (-525 1175)(-525 825);
WIRE 16 -1 (-2400 1825)(-2725 1825);
WIRE 16 -1 (-2725 1725)(-2725 1825);
WIRE 16 -1 (2775 1625)(2775 1725);
WIRE 16 -1 (2275 1625)(2775 1625);
WIRE 16 -1 (2275 1725)(2275 1625);
WIRE 16 -1 (2075 1625)(2275 1625);
WIRE 16 -1 (2075 1525)(2075 1625);
WIRE 16 -1 (1775 1625)(2075 1625);
WIRE 16 -1 (1775 1725)(1775 1625);
WIRE 16 -1 (1400 1625)(1775 1625);
WIRE 16 -1 (1400 1725)(1400 1625);
WIRE 16 -1 (1025 1625)(1400 1625);
WIRE 16 -1 (1025 1725)(1025 1625);
WIRE 16 -1 (925 2025)(1025 2025);
WIRE 16 -1 (1400 2025)(1025 2025);
WIRE 16 -1 (1025 1925)(1025 2025);
WIRE 16 -1 (1775 2025)(1400 2025);
WIRE 16 -1 (1400 1925)(1400 2025);
WIRE 16 -1 (2275 2025)(1775 2025);
WIRE 16 -1 (1775 1925)(1775 2025);
WIRE 16 -1 (2275 2125)(2275 2025);
WIRE 16 -1 (2775 2025)(2275 2025);
WIRE 16 -1 (2275 1925)(2275 2025);
WIRE 16 -1 (3325 2025)(2775 2025);
WIRE 16 -1 (2775 1925)(2775 2025);
WIRE 16 -1 (3325 1250)(3325 2025);
WIRE 16 -1 (2175 1250)(3325 1250);
WIRE 16 -1 (2175 825)(2175 1250);
WIRE 16 -1 (1625 1250)(2175 1250);
WIRE 16 -1 (1625 825)(2175 825);
WIRE 16 -1 (-4125 2725)(-3725 2725);
WIRE 16 -1 (-4125 2825)(-4125 2725);
WIRE 16 -1 (-4125 2725)(-4125 2625);
WIRE 16 -1 (-3325 2425)(-3325 2300);
WIRE 16 -1 (-3325 2300)(-2725 2300);
WIRE 16 -1 (-2725 2425)(-2725 2300);
WIRE 16 -1 (-2725 2300)(-2675 2300);
WIRE 16 -1 (-2125 2300)(-2675 2300);
WIRE 16 -1 (-2675 2300)(-2675 2225);
WIRE 16 -1 (-2125 2425)(-2125 2300);
WIRE 16 -1 (-2025 1225)(-1475 1225);
FORCEPROP 2 LAST SIG_NAME P1V8_AUX_CS
J 0
(-2010 1235);
DISPLAY 0.617021 (-2010 1235);
FORCEPROP 2 LASTPROP $XRERR UNIQUE?
J 0
(-2250 1235);
DISPLAY 0.638298 (-2250 1235);
PAINT MONO (-2250 1235);
DISPLAY INVISIBLE (-2250 1235);
WIRE 16 -1 (-2025 1075)(-2025 1225);
WIRE 16 -1 (-125 1325)(-125 1150);
WIRE 16 -1 (-675 1325)(-125 1325);
FORCEPROP 2 LAST SIG_NAME P1V8_AUX_REF
J 0
(-585 1335);
DISPLAY 0.617021 (-585 1335);
FORCEPROP 2 LASTPROP $XRERR UNIQUE?
J 0
(-825 1335);
DISPLAY 0.638298 (-825 1335);
PAINT MONO (-825 1335);
DISPLAY INVISIBLE (-825 1335);
WIRE 16 -1 (25 2525)(25 2725);
WIRE 16 -1 (25 2525)(250 2525);
WIRE 16 -1 (-675 2525)(25 2525);
FORCEPROP 2 LAST SIG_NAME PWRGD_P1V8_AUX
J 0
(-585 2535);
DISPLAY 0.617021 (-585 2535);
FORCEPROP 2 LASTPROP $XRERR UNIQUE?
J 0
(-825 2535);
DISPLAY 0.638298 (-825 2535);
PAINT MONO (-825 2535);
DISPLAY INVISIBLE (-825 2535);
WIRE 16 -1 (350 2325)(350 2300);
WIRE 16 -1 (0 2325)(350 2325);
FORCEPROP 2 LAST SIG_NAME SW_P1V8_AUX_BT_R
J 0
(15 2335);
DISPLAY 0.446809 (15 2335);
FORCEPROP 2 LASTPROP $XRERR UNIQUE?
J 0
(-225 2335);
DISPLAY 0.638298 (-225 2335);
PAINT MONO (-225 2335);
DISPLAY INVISIBLE (-225 2335);
WIRE 16 -1 (-675 2075)(350 2075);
WIRE 16 -1 (350 2075)(350 2100);
WIRE 16 -1 (350 2025)(350 2075);
WIRE 16 -1 (350 2025)(725 2025);
WIRE 16 -1 (-675 2025)(350 2025);
FORCEPROP 2 LAST SIG_NAME SW_P1V8_AUX_PH
J 0
(-585 1985);
DISPLAY 0.617021 (-585 1985);
FORCEPROP 2 LASTPROP $XRERR UNIQUE?
J 0
(-825 1985);
DISPLAY 0.638298 (-825 1985);
PAINT MONO (-825 1985);
DISPLAY INVISIBLE (-825 1985);
WIRE 16 -1 (-675 2325)(-200 2325);
FORCEPROP 2 LAST SIG_NAME SW_P1V8_AUX_BT
J 0
(-585 2335);
DISPLAY 0.489362 (-585 2335);
FORCEPROP 2 LASTPROP $XRERR UNIQUE?
J 0
(-825 2335);
DISPLAY 0.638298 (-825 2335);
PAINT MONO (-825 2335);
DISPLAY INVISIBLE (-825 2335);
WIRE 16 -1 (975 825)(1425 825);
WIRE 16 -1 (975 1250)(975 825);
WIRE 16 -1 (975 1250)(1425 1250);
WIRE 16 -1 (975 1250)(475 1250);
WIRE 16 -1 (275 1250)(475 1250);
WIRE 16 -1 (475 1000)(475 1250);
WIRE 16 -1 (275 1575)(275 1250);
WIRE 16 -1 (-675 1575)(275 1575);
FORCEPROP 2 LAST SIG_NAME P1V8_AUX_FB
J 0
(-585 1585);
DISPLAY 0.617021 (-585 1585);
FORCEPROP 2 LASTPROP $XRERR UNIQUE?
J 0
(-825 1585);
DISPLAY 0.638298 (-825 1585);
PAINT MONO (-825 1585);
DISPLAY INVISIBLE (-825 1585);
WIRE 16 2175 (-4875 5075)(-2765 5075);
WIRE 16 2175 (-4875 5075)(-4875 4125);
WIRE 16 2175 (-2765 5075)(-2765 4125);
WIRE 16 2175 (-4875 4125)(-2765 4125);
WIRE 16 -1 (-1825 2525)(-1475 2525);
WIRE 16 -1 (-1825 2725)(-1825 2525);
WIRE 16 -1 (-2125 2725)(-1825 2725);
WIRE 16 -1 (-2125 2725)(-2125 2625);
WIRE 16 -1 (-2125 2725)(-2725 2725);
WIRE 16 -1 (-2725 2625)(-2725 2725);
WIRE 16 -1 (-3325 2725)(-2725 2725);
FORCEPROP 2 LAST SIG_NAME SW_P12V_AUX_P1V8_AUX_FLT
J 0
(-3135 2735);
DISPLAY 0.617021 (-3135 2735);
FORCEPROP 2 LASTPROP $XRERR UNIQUE?
J 0
(-3375 2735);
DISPLAY 0.638298 (-3375 2735);
PAINT MONO (-3375 2735);
DISPLAY INVISIBLE (-3375 2735);
WIRE 16 -1 (-3325 2625)(-3325 2725);
WIRE 16 -1 (-3525 2725)(-3325 2725);
WIRE 16 -1 (-4000 2025)(-4775 2025);
FORCEPROP 2 LAST SIG_NAME PWRGD_P3V3_AUX
J 0
(-4710 2035);
DISPLAY 0.680851 (-4710 2035);
WIRE 16 -1 (-2200 1825)(-1475 1825);
FORCEPROP 2 LAST SIG_NAME P1V8_AUX_MODE
J 0
(-2010 1835);
DISPLAY 0.617021 (-2010 1835);
FORCEPROP 2 LASTPROP $XRERR UNIQUE?
J 0
(-2250 1835);
DISPLAY 0.638298 (-2250 1835);
PAINT MONO (-2250 1835);
DISPLAY INVISIBLE (-2250 1835);
WIRE 16 -1 (-2725 1575)(-2225 1575);
WIRE 16 -1 (-2225 1575)(-1475 1575);
FORCEPROP 2 LAST SIG_NAME P1V8_AUX_VCC
J 0
(-2010 1585);
DISPLAY 0.617021 (-2010 1585);
FORCEPROP 2 LASTPROP $XRERR UNIQUE?
J 0
(-2250 1585);
DISPLAY 0.638298 (-2250 1585);
PAINT MONO (-2250 1585);
DISPLAY INVISIBLE (-2250 1585);
WIRE 16 -1 (-2225 1475)(-2225 1575);
WIRE 16 -1 (1225 2525)(450 2525);
FORCEPROP 2 LAST SIG_NAME PWRGD_P1V8_AUX_R
J 0
(615 2535);
DISPLAY 0.680851 (615 2535);
DOT 1 (350 2075);
DOT 1 (350 2025);
DOT 1 (1025 2025);
DOT 1 (1400 1625);
DOT 1 (1400 2025);
DOT 1 (25 2525);
DOT 1 (-2675 2300);
DOT 1 (-525 1175);
DOT 1 (-2225 1575);
DOT 1 (-2125 2725);
DOT 1 (-3525 2025);
DOT 1 (975 1250);
DOT 1 (-2725 2725);
DOT 1 (475 1250);
DOT 1 (1775 1625);
DOT 1 (1775 2025);
DOT 1 (2175 1250);
DOT 1 (2075 1625);
DOT 1 (2275 1625);
DOT 1 (2275 2025);
DOT 1 (2775 2025);
DOT 1 (-4125 2725);
DOT 1 (-3325 2725);
DOT 1 (-2725 2300);
FORCENOTE
RCS=10K OCP=3A
(-1925 675) 0;
DISPLAY LEFT (-1925 675);
DISPLAY 0.808511 (-1925 675);
FORCENOTE
PCMC063T-3R3MN
(425 1825) 0;
DISPLAY LEFT (425 1825);
DISPLAY 0.808511 (425 1825);
FORCENOTE
DCR=30 MOHM
(425 1675) 0;
DISPLAY LEFT (425 1675);
DISPLAY 0.808511 (425 1675);
FORCENOTE
ISAT=12A @100C
(425 1750) 0;
DISPLAY LEFT (425 1750);
DISPLAY 0.808511 (425 1750);
FORCENOTE
7.3*6.6*3
(425 1900) 0;
DISPLAY LEFT (425 1900);
DISPLAY 0.808511 (425 1900);
FORCENOTE
ENABLE: VIH>1.27V
(-2300 2100) 0;
DISPLAY LEFT (-2300 2100);
DISPLAY 0.808511 (-2300 2100);
FORCENOTE
FCCM/FREQ.=600KHZ
(-3425 1850) 0;
DISPLAY LEFT (-3425 1850);
DISPLAY 0.808511 (-3425 1850);
FORCENOTE
R1
(1525 1425) 0;
DISPLAY LEFT (1525 1425);
DISPLAY 1.021277 (1525 1425);
FORCENOTE
OVER CURRENT PROTECTION(IMAX*1.3)=3A
(-4825 4450) 0;
DISPLAY LEFT (-4825 4450);
DISPLAY 1.170213 (-4825 4450);
PAINT WHITE (-4825 4450);
FORCENOTE
SLEW RATE=2.5A/US
(-4825 4375) 0;
DISPLAY LEFT (-4825 4375);
DISPLAY 1.170213 (-4825 4375);
PAINT WHITE (-4825 4375);
FORCENOTE
WORK FREQUENCY=600KHZ
(-4825 4275) 0;
DISPLAY LEFT (-4825 4275);
DISPLAY 1.276596 (-4825 4275);
PAINT WHITE (-4825 4275);
FORCENOTE
EFFICENCY>90%@TDC
(-4825 4175) 0;
DISPLAY LEFT (-4825 4175);
DISPLAY 1.170213 (-4825 4175);
PAINT WHITE (-4825 4175);
FORCENOTE
VOUT=0.6(1+R1/R2)=1.8V
(300 275) 0;
DISPLAY LEFT (300 275);
DISPLAY 1.595745 (300 275);
FORCENOTE
DESIGN SPECIFICATION
(-4825 4954) 0;
DISPLAY LEFT (-4825 4954);
DISPLAY 1.829787 (-4825 4954);
PAINT WHITE (-4825 4954);
FORCENOTE
OUTPUT VOLTAGE=1.8V +/-5%
(-4825 4850) 0;
DISPLAY LEFT (-4825 4850);
DISPLAY 1.170213 (-4825 4850);
PAINT WHITE (-4825 4850);
FORCENOTE
OUTPUT RIPPLE<30MV
(-4825 4779) 0;
DISPLAY LEFT (-4825 4779);
DISPLAY 1.170213 (-4825 4779);
PAINT WHITE (-4825 4779);
FORCENOTE
TRANSIENT TOLERANCE<100MV
(-4825 4696) 0;
DISPLAY LEFT (-4825 4696);
DISPLAY 1.170213 (-4825 4696);
PAINT WHITE (-4825 4696);
FORCENOTE
MAX CURRENT=2.0A
(-4825 4540) 0;
DISPLAY LEFT (-4825 4540);
DISPLAY 1.170213 (-4825 4540);
PAINT WHITE (-4825 4540);
FORCENOTE
TDC=2.0A
(-4825 4615) 0;
DISPLAY LEFT (-4825 4615);
DISPLAY 1.170213 (-4825 4615);
PAINT WHITE (-4825 4615);
FORCENOTE
R2
(700 1025) 0;
DISPLAY LEFT (700 1025);
DISPLAY 1.021277 (700 1025);
FORCENOTE
2ND 
(-4700 -600) 0;
DISPLAY LEFT (-4700 -600);
DISPLAY 1.170213 (-4700 -600);
PAINT WHITE (-4700 -600);
FORCENOTE
3RD 
(-4700 -675) 0;
DISPLAY LEFT (-4700 -675);
DISPLAY 1.170213 (-4700 -675);
PAINT WHITE (-4700 -675);
FORCENOTE
R&C TABLE
(-4700 -450) 0;
DISPLAY LEFT (-4700 -450);
DISPLAY 1.170213 (-4700 -450);
PAINT WHITE (-4700 -450);
FORCENOTE
1ST 
(-4700 -525) 0;
DISPLAY LEFT (-4700 -525);
DISPLAY 1.170213 (-4700 -525);
PAINT WHITE (-4700 -525);
FORCENOTE
IC TABLE
(-4650 200) 0;
DISPLAY LEFT (-4650 200);
DISPLAY 1.170213 (-4650 200);
PAINT WHITE (-4650 200);
FORCENOTE
3RD AL54J061000/TPS54J061RPGR/TI
(-4650 -25) 0;
DISPLAY LEFT (-4650 -25);
DISPLAY 1.021277 (-4650 -25);
PAINT WHITE (-4650 -25);
FORCENOTE
2ND AL053317005/RS53317LR/REEDSEMI
(-4650 50) 0;
DISPLAY LEFT (-4650 50);
DISPLAY 1.021277 (-4650 50);
PAINT WHITE (-4650 50);
FORCENOTE
1ST AL008626000/MPQ8626GD-Z/MPS
(-4650 125) 0;
DISPLAY LEFT (-4650 125);
DISPLAY 1.021277 (-4650 125);
PAINT WHITE (-4650 125);
QUIT
